G04 ================== begin FILE IDENTIFICATION RECORD ==================*
G04 Layout Name:  D:/<user>/Wistron_project/16369-sd/gbr/16369-sd.brd*
G04 Film Name:    L1*
G04 File Format:  Gerber RS274X*
G04 File Origin:  Cadence Allegro 16.5-S056*
G04 Origin Date:  Wed Mar 29 13:12:52 2017*
G04 *
G04 Layer:  VIA CLASS/TOP*
G04 Layer:  PIN/TOP*
G04 Layer:  ETCH/TOP*
G04 Layer:  DRAWING FORMAT/LAYER_PCB_STORY*
G04 Layer:  DRAWING FORMAT/LAYER_L1*
G04 *
G04 Offset:    (0.00 0.00)*
G04 Mirror:    No*
G04 Mode:      Positive*
G04 Rotation:  0*
G04 FullContactRelief:  No*
G04 UndefLineWidth:     6.00*
G04 ================== end FILE IDENTIFICATION RECORD ====================*
%FSLAX35Y35*MOIN*%
%IR0*IPPOS*OFA0.00000B0.00000*MIA0B0*SFA1.00000B1.00000*%
%AMMACRO64*
4,1,40,.017,-.013,
.017,.013,
.016939,.013695,
.016759,.014368,
.016464,.015,
.016064,.015571,
.015571,.016064,
.015,.016464,
.014368,.016759,
.013695,.016939,
.013,.017,
-.013,.017,
-.013695,.016939,
-.014368,.016759,
-.015,.016464,
-.015571,.016064,
-.016064,.015571,
-.016464,.015,
-.016759,.014368,
-.016939,.013695,
-.017,.013,
-.017,-.013,
-.016939,-.013695,
-.016759,-.014368,
-.016464,-.015,
-.016064,-.015571,
-.015571,-.016064,
-.015,-.016464,
-.014368,-.016759,
-.013695,-.016939,
-.013,-.017,
.013,-.017,
.013695,-.016939,
.014368,-.016759,
.015,-.016464,
.015571,-.016064,
.016064,-.015571,
.016464,-.015,
.016759,-.014368,
.016939,-.013695,
.017,-.013,
0.0*
%
%ADD64MACRO64*%
%AMMACRO44*
4,1,40,.013,.017,
-.013,.017,
-.013695,.016939,
-.014368,.016759,
-.015,.016464,
-.015571,.016064,
-.016064,.015571,
-.016464,.015,
-.016759,.014368,
-.016939,.013695,
-.017,.013,
-.017,-.013,
-.016939,-.013695,
-.016759,-.014368,
-.016464,-.015,
-.016064,-.015571,
-.015571,-.016064,
-.015,-.016464,
-.014368,-.016759,
-.013695,-.016939,
-.013,-.017,
.013,-.017,
.013695,-.016939,
.014368,-.016759,
.015,-.016464,
.015571,-.016064,
.016064,-.015571,
.016464,-.015,
.016759,-.014368,
.016939,-.013695,
.017,-.013,
.017,.013,
.016939,.013695,
.016759,.014368,
.016464,.015,
.016064,.015571,
.015571,.016064,
.015,.016464,
.014368,.016759,
.013695,.016939,
.013,.017,
0.0*
%
%ADD44MACRO44*%
%AMMACRO65*
4,1,40,.008,.009,
.008695,.008939,
.009368,.008759,
.01,.008464,
.010571,.008064,
.011064,.007571,
.011464,.007,
.011759,.006368,
.011939,.005695,
.012,.005,
.012,-.005,
.011939,-.005695,
.011759,-.006368,
.011464,-.007,
.011064,-.007571,
.010571,-.008064,
.01,-.008464,
.009368,-.008759,
.008695,-.008939,
.008,-.009,
-.008,-.009,
-.008695,-.008939,
-.009368,-.008759,
-.01,-.008464,
-.010571,-.008064,
-.011064,-.007571,
-.011464,-.007,
-.011759,-.006368,
-.011939,-.005695,
-.012,-.005,
-.012,.005,
-.011939,.005695,
-.011759,.006368,
-.011464,.007,
-.011064,.007571,
-.010571,.008064,
-.01,.008464,
-.009368,.008759,
-.008695,.008939,
-.008,.009,
.008,.009,
0.0*
%
%ADD65MACRO65*%
%ADD10C,.01*%
%ADD27C,.02*%
%ADD13C,.022*%
%ADD11C,.04*%
%ADD45C,.032*%
%ADD46C,.042*%
%ADD55C,.052*%
%ADD28C,.026*%
%ADD48C,.028*%
%ADD42C,.046*%
%AMMACRO34*
4,1,40,.011,-.007,
.011,.007,
.010939,.007695,
.010759,.008368,
.010464,.009,
.010064,.009571,
.009571,.010064,
.009,.010464,
.008368,.010759,
.007695,.010939,
.007,.011,
-.007,.011,
-.007695,.010939,
-.008368,.010759,
-.009,.010464,
-.009571,.010064,
-.010064,.009571,
-.010464,.009,
-.010759,.008368,
-.010939,.007695,
-.011,.007,
-.011,-.007,
-.010939,-.007695,
-.010759,-.008368,
-.010464,-.009,
-.010064,-.009571,
-.009571,-.010064,
-.009,-.010464,
-.008368,-.010759,
-.007695,-.010939,
-.007,-.011,
.007,-.011,
.007695,-.010939,
.008368,-.010759,
.009,-.010464,
.009571,-.010064,
.010064,-.009571,
.010464,-.009,
.010759,-.008368,
.010939,-.007695,
.011,-.007,
0.0*
%
%ADD34MACRO34*%
%AMMACRO18*
4,1,40,.007,.011,
-.007,.011,
-.007695,.010939,
-.008368,.010759,
-.009,.010464,
-.009571,.010064,
-.010064,.009571,
-.010464,.009,
-.010759,.008368,
-.010939,.007695,
-.011,.007,
-.011,-.007,
-.010939,-.007695,
-.010759,-.008368,
-.010464,-.009,
-.010064,-.009571,
-.009571,-.010064,
-.009,-.010464,
-.008368,-.010759,
-.007695,-.010939,
-.007,-.011,
.007,-.011,
.007695,-.010939,
.008368,-.010759,
.009,-.010464,
.009571,-.010064,
.010064,-.009571,
.010464,-.009,
.010759,-.008368,
.010939,-.007695,
.011,-.007,
.011,.007,
.010939,.007695,
.010759,.008368,
.010464,.009,
.010064,.009571,
.009571,.010064,
.009,.010464,
.008368,.010759,
.007695,.010939,
.007,.011,
0.0*
%
%ADD18MACRO18*%
%AMMACRO37*
4,1,40,-.012,.008,
-.012,-.008,
-.011939,-.008695,
-.011759,-.009368,
-.011464,-.01,
-.011064,-.010571,
-.010571,-.011064,
-.01,-.011464,
-.009368,-.011759,
-.008695,-.011939,
-.008,-.012,
.008,-.012,
.008695,-.011939,
.009368,-.011759,
.01,-.011464,
.010571,-.011064,
.011064,-.010571,
.011464,-.01,
.011759,-.009368,
.011939,-.008695,
.012,-.008,
.012,.008,
.011939,.008695,
.011759,.009368,
.011464,.01,
.011064,.010571,
.010571,.011064,
.01,.011464,
.009368,.011759,
.008695,.011939,
.008,.012,
-.008,.012,
-.008695,.011939,
-.009368,.011759,
-.01,.011464,
-.010571,.011064,
-.011064,.010571,
-.011464,.01,
-.011759,.009368,
-.011939,.008695,
-.012,.008,
0.0*
%
%ADD37MACRO37*%
%AMMACRO25*
4,1,40,.008,.012,
-.008,.012,
-.008695,.011939,
-.009368,.011759,
-.01,.011464,
-.010571,.011064,
-.011064,.010571,
-.011464,.01,
-.011759,.009368,
-.011939,.008695,
-.012,.008,
-.012,-.008,
-.011939,-.008695,
-.011759,-.009368,
-.011464,-.01,
-.011064,-.010571,
-.010571,-.011064,
-.01,-.011464,
-.009368,-.011759,
-.008695,-.011939,
-.008,-.012,
.008,-.012,
.008695,-.011939,
.009368,-.011759,
.01,-.011464,
.010571,-.011064,
.011064,-.010571,
.011464,-.01,
.011759,-.009368,
.011939,-.008695,
.012,-.008,
.012,.008,
.011939,.008695,
.011759,.009368,
.011464,.01,
.011064,.010571,
.010571,.011064,
.01,.011464,
.009368,.011759,
.008695,.011939,
.008,.012,
0.0*
%
%ADD25MACRO25*%
%AMMACRO49*
4,1,40,-.013,-.017,
.013,-.017,
.013695,-.016939,
.014368,-.016759,
.015,-.016464,
.015571,-.016064,
.016064,-.015571,
.016464,-.015,
.016759,-.014368,
.016939,-.013695,
.017,-.013,
.017,.013,
.016939,.013695,
.016759,.014368,
.016464,.015,
.016064,.015571,
.015571,.016064,
.015,.016464,
.014368,.016759,
.013695,.016939,
.013,.017,
-.013,.017,
-.013695,.016939,
-.014368,.016759,
-.015,.016464,
-.015571,.016064,
-.016064,.015571,
-.016464,.015,
-.016759,.014368,
-.016939,.013695,
-.017,.013,
-.017,-.013,
-.016939,-.013695,
-.016759,-.014368,
-.016464,-.015,
-.016064,-.015571,
-.015571,-.016064,
-.015,-.016464,
-.014368,-.016759,
-.013695,-.016939,
-.013,-.017,
0.0*
%
%ADD49MACRO49*%
%AMMACRO60*
4,1,40,-.017,.013,
-.017,-.013,
-.016939,-.013695,
-.016759,-.014368,
-.016464,-.015,
-.016064,-.015571,
-.015571,-.016064,
-.015,-.016464,
-.014368,-.016759,
-.013695,-.016939,
-.013,-.017,
.013,-.017,
.013695,-.016939,
.014368,-.016759,
.015,-.016464,
.015571,-.016064,
.016064,-.015571,
.016464,-.015,
.016759,-.014368,
.016939,-.013695,
.017,-.013,
.017,.013,
.016939,.013695,
.016759,.014368,
.016464,.015,
.016064,.015571,
.015571,.016064,
.015,.016464,
.014368,.016759,
.013695,.016939,
.013,.017,
-.013,.017,
-.013695,.016939,
-.014368,.016759,
-.015,.016464,
-.015571,.016064,
-.016064,.015571,
-.016464,.015,
-.016759,.014368,
-.016939,.013695,
-.017,.013,
0.0*
%
%ADD60MACRO60*%
%AMMACRO51*
4,1,40,.008,.009,
.008695,.008939,
.009368,.008759,
.01,.008464,
.010571,.008064,
.011064,.007571,
.011464,.007,
.011759,.006368,
.011939,.005695,
.012,.005,
.012,-.005,
.011939,-.005695,
.011759,-.006368,
.011464,-.007,
.011064,-.007571,
.010571,-.008064,
.01,-.008464,
.009368,-.008759,
.008695,-.008939,
.008,-.009,
-.008,-.009,
-.008695,-.008939,
-.009368,-.008759,
-.01,-.008464,
-.010571,-.008064,
-.011064,-.007571,
-.011464,-.007,
-.011759,-.006368,
-.011939,-.005695,
-.012,-.005,
-.012,.005,
-.011939,.005695,
-.011759,.006368,
-.011464,.007,
-.011064,.007571,
-.010571,.008064,
-.01,.008464,
-.009368,.008759,
-.008695,.008939,
-.008,.009,
.008,.009,
0.0*
%
%ADD51MACRO51*%
%AMMACRO35*
4,1,40,.011,-.007,
.011,.007,
.010939,.007695,
.010759,.008368,
.010464,.009,
.010064,.009571,
.009571,.010064,
.009,.010464,
.008368,.010759,
.007695,.010939,
.007,.011,
-.007,.011,
-.007695,.010939,
-.008368,.010759,
-.009,.010464,
-.009571,.010064,
-.010064,.009571,
-.010464,.009,
-.010759,.008368,
-.010939,.007695,
-.011,.007,
-.011,-.007,
-.010939,-.007695,
-.010759,-.008368,
-.010464,-.009,
-.010064,-.009571,
-.009571,-.010064,
-.009,-.010464,
-.008368,-.010759,
-.007695,-.010939,
-.007,-.011,
.007,-.011,
.007695,-.010939,
.008368,-.010759,
.009,-.010464,
.009571,-.010064,
.010064,-.009571,
.010464,-.009,
.010759,-.008368,
.010939,-.007695,
.011,-.007,
0.0*
%
%ADD35MACRO35*%
%AMMACRO19*
4,1,40,.007,.011,
-.007,.011,
-.007695,.010939,
-.008368,.010759,
-.009,.010464,
-.009571,.010064,
-.010064,.009571,
-.010464,.009,
-.010759,.008368,
-.010939,.007695,
-.011,.007,
-.011,-.007,
-.010939,-.007695,
-.010759,-.008368,
-.010464,-.009,
-.010064,-.009571,
-.009571,-.010064,
-.009,-.010464,
-.008368,-.010759,
-.007695,-.010939,
-.007,-.011,
.007,-.011,
.007695,-.010939,
.008368,-.010759,
.009,-.010464,
.009571,-.010064,
.010064,-.009571,
.010464,-.009,
.010759,-.008368,
.010939,-.007695,
.011,-.007,
.011,.007,
.010939,.007695,
.010759,.008368,
.010464,.009,
.010064,.009571,
.009571,.010064,
.009,.010464,
.008368,.010759,
.007695,.010939,
.007,.011,
0.0*
%
%ADD19MACRO19*%
%AMMACRO36*
4,1,40,-.012,.008,
-.012,-.008,
-.011939,-.008695,
-.011759,-.009368,
-.011464,-.01,
-.011064,-.010571,
-.010571,-.011064,
-.01,-.011464,
-.009368,-.011759,
-.008695,-.011939,
-.008,-.012,
.008,-.012,
.008695,-.011939,
.009368,-.011759,
.01,-.011464,
.010571,-.011064,
.011064,-.010571,
.011464,-.01,
.011759,-.009368,
.011939,-.008695,
.012,-.008,
.012,.008,
.011939,.008695,
.011759,.009368,
.011464,.01,
.011064,.010571,
.010571,.011064,
.01,.011464,
.009368,.011759,
.008695,.011939,
.008,.012,
-.008,.012,
-.008695,.011939,
-.009368,.011759,
-.01,.011464,
-.010571,.011064,
-.011064,.010571,
-.011464,.01,
-.011759,.009368,
-.011939,.008695,
-.012,.008,
0.0*
%
%ADD36MACRO36*%
%AMMACRO24*
4,1,40,.008,.012,
-.008,.012,
-.008695,.011939,
-.009368,.011759,
-.01,.011464,
-.010571,.011064,
-.011064,.010571,
-.011464,.01,
-.011759,.009368,
-.011939,.008695,
-.012,.008,
-.012,-.008,
-.011939,-.008695,
-.011759,-.009368,
-.011464,-.01,
-.011064,-.010571,
-.010571,-.011064,
-.01,-.011464,
-.009368,-.011759,
-.008695,-.011939,
-.008,-.012,
.008,-.012,
.008695,-.011939,
.009368,-.011759,
.01,-.011464,
.010571,-.011064,
.011064,-.010571,
.011464,-.01,
.011759,-.009368,
.011939,-.008695,
.012,-.008,
.012,.008,
.011939,.008695,
.011759,.009368,
.011464,.01,
.011064,.010571,
.010571,.011064,
.01,.011464,
.009368,.011759,
.008695,.011939,
.008,.012,
0.0*
%
%ADD24MACRO24*%
%AMMACRO50*
4,1,40,-.013,-.017,
.013,-.017,
.013695,-.016939,
.014368,-.016759,
.015,-.016464,
.015571,-.016064,
.016064,-.015571,
.016464,-.015,
.016759,-.014368,
.016939,-.013695,
.017,-.013,
.017,.013,
.016939,.013695,
.016759,.014368,
.016464,.015,
.016064,.015571,
.015571,.016064,
.015,.016464,
.014368,.016759,
.013695,.016939,
.013,.017,
-.013,.017,
-.013695,.016939,
-.014368,.016759,
-.015,.016464,
-.015571,.016064,
-.016064,.015571,
-.016464,.015,
-.016759,.014368,
-.016939,.013695,
-.017,.013,
-.017,-.013,
-.016939,-.013695,
-.016759,-.014368,
-.016464,-.015,
-.016064,-.015571,
-.015571,-.016064,
-.015,-.016464,
-.014368,-.016759,
-.013695,-.016939,
-.013,-.017,
0.0*
%
%ADD50MACRO50*%
%AMMACRO61*
4,1,40,-.017,.013,
-.017,-.013,
-.016939,-.013695,
-.016759,-.014368,
-.016464,-.015,
-.016064,-.015571,
-.015571,-.016064,
-.015,-.016464,
-.014368,-.016759,
-.013695,-.016939,
-.013,-.017,
.013,-.017,
.013695,-.016939,
.014368,-.016759,
.015,-.016464,
.015571,-.016064,
.016064,-.015571,
.016464,-.015,
.016759,-.014368,
.016939,-.013695,
.017,-.013,
.017,.013,
.016939,.013695,
.016759,.014368,
.016464,.015,
.016064,.015571,
.015571,.016064,
.015,.016464,
.014368,.016759,
.013695,.016939,
.013,.017,
-.013,.017,
-.013695,.016939,
-.014368,.016759,
-.015,.016464,
-.015571,.016064,
-.016064,.015571,
-.016464,.015,
-.016759,.014368,
-.016939,.013695,
-.017,.013,
0.0*
%
%ADD61MACRO61*%
%AMMACRO54*
4,1,40,-.008,-.009,
-.008695,-.008939,
-.009368,-.008759,
-.01,-.008464,
-.010571,-.008064,
-.011064,-.007571,
-.011464,-.007,
-.011759,-.006368,
-.011939,-.005695,
-.012,-.005,
-.012,.005,
-.011939,.005695,
-.011759,.006368,
-.011464,.007,
-.011064,.007571,
-.010571,.008064,
-.01,.008464,
-.009368,.008759,
-.008695,.008939,
-.008,.009,
.008,.009,
.008695,.008939,
.009368,.008759,
.01,.008464,
.010571,.008064,
.011064,.007571,
.011464,.007,
.011759,.006368,
.011939,.005695,
.012,.005,
.012,-.005,
.011939,-.005695,
.011759,-.006368,
.011464,-.007,
.011064,-.007571,
.010571,-.008064,
.01,-.008464,
.009368,-.008759,
.008695,-.008939,
.008,-.009,
-.008,-.009,
0.0*
%
%ADD54MACRO54*%
%ADD12R,.102X.134*%
%ADD59R,.04X.022*%
%ADD31R,.015X.012*%
%ADD30R,.022X.04*%
%ADD17R,.06X.012*%
%ADD56R,.012X.06*%
%ADD15R,.06X.014*%
%ADD57R,.02X.063*%
%ADD41R,.012X.036*%
%ADD40R,.061X.051*%
%ADD52R,.05X.065*%
%ADD14R,.024X.063*%
%ADD47C,.107*%
%ADD62R,.045X.055*%
%ADD29R,.048X.016*%
%ADD53R,.055X.045*%
%ADD16R,.016X.048*%
%ADD58C,.363*%
%ADD26R,.272X.272*%
%AMMACRO39*
4,1,40,-.008,-.012,
.008,-.012,
.008695,-.011939,
.009368,-.011759,
.01,-.011464,
.010571,-.011064,
.011064,-.010571,
.011464,-.01,
.011759,-.009368,
.011939,-.008695,
.012,-.008,
.012,.008,
.011939,.008695,
.011759,.009368,
.011464,.01,
.011064,.010571,
.010571,.011064,
.01,.011464,
.009368,.011759,
.008695,.011939,
.008,.012,
-.008,.012,
-.008695,.011939,
-.009368,.011759,
-.01,.011464,
-.010571,.011064,
-.011064,.010571,
-.011464,.01,
-.011759,.009368,
-.011939,.008695,
-.012,.008,
-.012,-.008,
-.011939,-.008695,
-.011759,-.009368,
-.011464,-.01,
-.011064,-.010571,
-.010571,-.011064,
-.01,-.011464,
-.009368,-.011759,
-.008695,-.011939,
-.008,-.012,
0.0*
%
%ADD39MACRO39*%
%AMMACRO23*
4,1,40,.012,-.008,
.012,.008,
.011939,.008695,
.011759,.009368,
.011464,.01,
.011064,.010571,
.010571,.011064,
.01,.011464,
.009368,.011759,
.008695,.011939,
.008,.012,
-.008,.012,
-.008695,.011939,
-.009368,.011759,
-.01,.011464,
-.010571,.011064,
-.011064,.010571,
-.011464,.01,
-.011759,.009368,
-.011939,.008695,
-.012,.008,
-.012,-.008,
-.011939,-.008695,
-.011759,-.009368,
-.011464,-.01,
-.011064,-.010571,
-.010571,-.011064,
-.01,-.011464,
-.009368,-.011759,
-.008695,-.011939,
-.008,-.012,
.008,-.012,
.008695,-.011939,
.009368,-.011759,
.01,-.011464,
.010571,-.011064,
.011064,-.010571,
.011464,-.01,
.011759,-.009368,
.011939,-.008695,
.012,-.008,
0.0*
%
%ADD23MACRO23*%
%AMMACRO20*
4,1,40,-.007,-.011,
.007,-.011,
.007695,-.010939,
.008368,-.010759,
.009,-.010464,
.009571,-.010064,
.010064,-.009571,
.010464,-.009,
.010759,-.008368,
.010939,-.007695,
.011,-.007,
.011,.007,
.010939,.007695,
.010759,.008368,
.010464,.009,
.010064,.009571,
.009571,.010064,
.009,.010464,
.008368,.010759,
.007695,.010939,
.007,.011,
-.007,.011,
-.007695,.010939,
-.008368,.010759,
-.009,.010464,
-.009571,.010064,
-.010064,.009571,
-.010464,.009,
-.010759,.008368,
-.010939,.007695,
-.011,.007,
-.011,-.007,
-.010939,-.007695,
-.010759,-.008368,
-.010464,-.009,
-.010064,-.009571,
-.009571,-.010064,
-.009,-.010464,
-.008368,-.010759,
-.007695,-.010939,
-.007,-.011,
0.0*
%
%ADD20MACRO20*%
%AMMACRO32*
4,1,40,-.011,.007,
-.011,-.007,
-.010939,-.007695,
-.010759,-.008368,
-.010464,-.009,
-.010064,-.009571,
-.009571,-.010064,
-.009,-.010464,
-.008368,-.010759,
-.007695,-.010939,
-.007,-.011,
.007,-.011,
.007695,-.010939,
.008368,-.010759,
.009,-.010464,
.009571,-.010064,
.010064,-.009571,
.010464,-.009,
.010759,-.008368,
.010939,-.007695,
.011,-.007,
.011,.007,
.010939,.007695,
.010759,.008368,
.010464,.009,
.010064,.009571,
.009571,.010064,
.009,.010464,
.008368,.010759,
.007695,.010939,
.007,.011,
-.007,.011,
-.007695,.010939,
-.008368,.010759,
-.009,.010464,
-.009571,.010064,
-.010064,.009571,
-.010464,.009,
-.010759,.008368,
-.010939,.007695,
-.011,.007,
0.0*
%
%ADD32MACRO32*%
%AMMACRO63*
4,1,40,.017,-.013,
.017,.013,
.016939,.013695,
.016759,.014368,
.016464,.015,
.016064,.015571,
.015571,.016064,
.015,.016464,
.014368,.016759,
.013695,.016939,
.013,.017,
-.013,.017,
-.013695,.016939,
-.014368,.016759,
-.015,.016464,
-.015571,.016064,
-.016064,.015571,
-.016464,.015,
-.016759,.014368,
-.016939,.013695,
-.017,.013,
-.017,-.013,
-.016939,-.013695,
-.016759,-.014368,
-.016464,-.015,
-.016064,-.015571,
-.015571,-.016064,
-.015,-.016464,
-.014368,-.016759,
-.013695,-.016939,
-.013,-.017,
.013,-.017,
.013695,-.016939,
.014368,-.016759,
.015,-.016464,
.015571,-.016064,
.016064,-.015571,
.016464,-.015,
.016759,-.014368,
.016939,-.013695,
.017,-.013,
0.0*
%
%ADD63MACRO63*%
%AMMACRO43*
4,1,40,.013,.017,
-.013,.017,
-.013695,.016939,
-.014368,.016759,
-.015,.016464,
-.015571,.016064,
-.016064,.015571,
-.016464,.015,
-.016759,.014368,
-.016939,.013695,
-.017,.013,
-.017,-.013,
-.016939,-.013695,
-.016759,-.014368,
-.016464,-.015,
-.016064,-.015571,
-.015571,-.016064,
-.015,-.016464,
-.014368,-.016759,
-.013695,-.016939,
-.013,-.017,
.013,-.017,
.013695,-.016939,
.014368,-.016759,
.015,-.016464,
.015571,-.016064,
.016064,-.015571,
.016464,-.015,
.016759,-.014368,
.016939,-.013695,
.017,-.013,
.017,.013,
.016939,.013695,
.016759,.014368,
.016464,.015,
.016064,.015571,
.015571,.016064,
.015,.016464,
.014368,.016759,
.013695,.016939,
.013,.017,
0.0*
%
%ADD43MACRO43*%
%AMMACRO66*
4,1,40,-.008,-.009,
-.008695,-.008939,
-.009368,-.008759,
-.01,-.008464,
-.010571,-.008064,
-.011064,-.007571,
-.011464,-.007,
-.011759,-.006368,
-.011939,-.005695,
-.012,-.005,
-.012,.005,
-.011939,.005695,
-.011759,.006368,
-.011464,.007,
-.011064,.007571,
-.010571,.008064,
-.01,.008464,
-.009368,.008759,
-.008695,.008939,
-.008,.009,
.008,.009,
.008695,.008939,
.009368,.008759,
.01,.008464,
.010571,.008064,
.011064,.007571,
.011464,.007,
.011759,.006368,
.011939,.005695,
.012,.005,
.012,-.005,
.011939,-.005695,
.011759,-.006368,
.011464,-.007,
.011064,-.007571,
.010571,-.008064,
.01,-.008464,
.009368,-.008759,
.008695,-.008939,
.008,-.009,
-.008,-.009,
0.0*
%
%ADD66MACRO66*%
%AMMACRO38*
4,1,40,-.008,-.012,
.008,-.012,
.008695,-.011939,
.009368,-.011759,
.01,-.011464,
.010571,-.011064,
.011064,-.010571,
.011464,-.01,
.011759,-.009368,
.011939,-.008695,
.012,-.008,
.012,.008,
.011939,.008695,
.011759,.009368,
.011464,.01,
.011064,.010571,
.010571,.011064,
.01,.011464,
.009368,.011759,
.008695,.011939,
.008,.012,
-.008,.012,
-.008695,.011939,
-.009368,.011759,
-.01,.011464,
-.010571,.011064,
-.011064,.010571,
-.011464,.01,
-.011759,.009368,
-.011939,.008695,
-.012,.008,
-.012,-.008,
-.011939,-.008695,
-.011759,-.009368,
-.011464,-.01,
-.011064,-.010571,
-.010571,-.011064,
-.01,-.011464,
-.009368,-.011759,
-.008695,-.011939,
-.008,-.012,
0.0*
%
%ADD38MACRO38*%
%AMMACRO22*
4,1,40,.012,-.008,
.012,.008,
.011939,.008695,
.011759,.009368,
.011464,.01,
.011064,.010571,
.010571,.011064,
.01,.011464,
.009368,.011759,
.008695,.011939,
.008,.012,
-.008,.012,
-.008695,.011939,
-.009368,.011759,
-.01,.011464,
-.010571,.011064,
-.011064,.010571,
-.011464,.01,
-.011759,.009368,
-.011939,.008695,
-.012,.008,
-.012,-.008,
-.011939,-.008695,
-.011759,-.009368,
-.011464,-.01,
-.011064,-.010571,
-.010571,-.011064,
-.01,-.011464,
-.009368,-.011759,
-.008695,-.011939,
-.008,-.012,
.008,-.012,
.008695,-.011939,
.009368,-.011759,
.01,-.011464,
.010571,-.011064,
.011064,-.010571,
.011464,-.01,
.011759,-.009368,
.011939,-.008695,
.012,-.008,
0.0*
%
%ADD22MACRO22*%
%AMMACRO21*
4,1,40,-.007,-.011,
.007,-.011,
.007695,-.010939,
.008368,-.010759,
.009,-.010464,
.009571,-.010064,
.010064,-.009571,
.010464,-.009,
.010759,-.008368,
.010939,-.007695,
.011,-.007,
.011,.007,
.010939,.007695,
.010759,.008368,
.010464,.009,
.010064,.009571,
.009571,.010064,
.009,.010464,
.008368,.010759,
.007695,.010939,
.007,.011,
-.007,.011,
-.007695,.010939,
-.008368,.010759,
-.009,.010464,
-.009571,.010064,
-.010064,.009571,
-.010464,.009,
-.010759,.008368,
-.010939,.007695,
-.011,.007,
-.011,-.007,
-.010939,-.007695,
-.010759,-.008368,
-.010464,-.009,
-.010064,-.009571,
-.009571,-.010064,
-.009,-.010464,
-.008368,-.010759,
-.007695,-.010939,
-.007,-.011,
0.0*
%
%ADD21MACRO21*%
%AMMACRO33*
4,1,40,-.011,.007,
-.011,-.007,
-.010939,-.007695,
-.010759,-.008368,
-.010464,-.009,
-.010064,-.009571,
-.009571,-.010064,
-.009,-.010464,
-.008368,-.010759,
-.007695,-.010939,
-.007,-.011,
.007,-.011,
.007695,-.010939,
.008368,-.010759,
.009,-.010464,
.009571,-.010064,
.010064,-.009571,
.010464,-.009,
.010759,-.008368,
.010939,-.007695,
.011,-.007,
.011,.007,
.010939,.007695,
.010759,.008368,
.010464,.009,
.010064,.009571,
.009571,.010064,
.009,.010464,
.008368,.010759,
.007695,.010939,
.007,.011,
-.007,.011,
-.007695,.010939,
-.008368,.010759,
-.009,.010464,
-.009571,.010064,
-.010064,.009571,
-.010464,.009,
-.010759,.008368,
-.010939,.007695,
-.011,.007,
0.0*
%
%ADD33MACRO33*%
%ADD67C,.03*%
%ADD68C,.012*%
%ADD69C,.014*%
%ADD70C,.015*%
%ADD71C,.016*%
%ADD72C,.006*%
%ADD73C,.00675*%
%ADD80R,.02X.008*%
%ADD78C,.09204*%
%ADD76C,.06604*%
%ADD79C,.07604*%
%ADD74C,.11004*%
%ADD77R,.008X.008*%
%ADD75C,.38704*%
G75*
%LPD*%
G75*
G36*
G01X3937Y-23377D02*
G02X3001Y-22441I0J936D01*
G01Y65628D01*
X4000Y66627D01*
X20873D01*
X22874Y64626D01*
Y50000D01*
X22872Y49998D01*
Y43372D01*
X21600Y42100D01*
X6000D01*
X5500Y41600D01*
Y41402D01*
X5498D01*
Y11702D01*
X6300Y10900D01*
X35900D01*
X36600Y10200D01*
Y4900D01*
X36000Y4300D01*
X31100D01*
X30300Y3500D01*
Y3378D01*
X30213Y3319D01*
G03X28042Y-787I2799J-4107D01*
G01Y-23377D01*
X3937D01*
G37*
G36*
G01X14100Y125300D02*
X13554Y125846D01*
Y131954D01*
X14000Y132400D01*
X51500D01*
X51900Y132000D01*
Y126100D01*
X51100Y125300D01*
X14100D01*
G37*
G36*
G01X95320Y93905D02*
X95318Y93907D01*
Y96271D01*
X61708Y129881D01*
Y129897D01*
X61734Y129923D01*
Y129934D01*
X62500Y130700D01*
X65200D01*
X95100Y100800D01*
X137400D01*
X163800Y127200D01*
X166100D01*
X167300Y126000D01*
Y122000D01*
X137300Y92000D01*
Y61147D01*
X133153Y57000D01*
X106600D01*
X97356Y66244D01*
Y67021D01*
X95320Y69057D01*
Y93905D01*
G37*
G36*
G01X30426Y227152D02*
X36597Y233323D01*
X36726Y233260D01*
G03X39600Y239205I1463J2960D01*
G01Y241109D01*
G03Y247079I-1411J2985D01*
G01Y248983D01*
G03X40595Y254229I-1411J2985D01*
G02X40844Y254901I291J274D01*
G03X33615Y261053I-687J6516D01*
G02X33216Y260630I-399J-23D01*
G01X31350D01*
G02X30951Y261053I0J400D01*
G03X18360Y258899I-6542J364D01*
G02X17991Y258345I-369J-154D01*
G01X16254D01*
X14870Y259729D01*
Y267010D01*
X19211Y271351D01*
X30568D01*
X32599Y273382D01*
Y283216D01*
G03X32602Y283300I-1598J99D01*
G01Y284700D01*
G03X32599Y284784I-1601J-15D01*
G01Y285232D01*
X33640Y286273D01*
X38280D01*
X53843Y270710D01*
Y216416D01*
X47343Y209916D01*
G02X46663Y210246I-283J283D01*
G03X40844Y217539I-6506J777D01*
G02X40595Y218211I42J398D01*
G03X36886Y217438I-2406J2261D01*
G02X36925Y216723I-158J-367D01*
G03X36068Y216142I3237J-5697D01*
G01X28498D01*
G03X30951Y211387I-4089J-5120D01*
G02X31350Y211810I399J23D01*
G01X33216D01*
G02X33615Y211387I0J-400D01*
G03X36645Y205492I6542J-364D01*
G02X36713Y204871I-215J-338D01*
G01X36155Y204314D01*
X32741D01*
X30847Y202419D01*
X18881D01*
X17738Y203562D01*
X17726Y203581D01*
G03X17021Y204286I-1869J-1164D01*
G01X17002Y204298D01*
X15778Y205522D01*
Y212948D01*
X23637Y220807D01*
X25476D01*
G03X30426Y225005I2870J1633D01*
G01Y227152D01*
G37*
G36*
G01X5231Y240768D02*
X3489D01*
X3089Y241168D01*
Y260045D01*
X3689Y260645D01*
X8383D01*
X8935Y260093D01*
Y244472D01*
X8020Y243556D01*
X7103D01*
X6315Y242768D01*
Y241852D01*
X5231Y240768D01*
G37*
G36*
G01X22300Y273000D02*
X21500Y273800D01*
Y284500D01*
X22100Y285100D01*
X31100D01*
X31398Y284802D01*
Y274098D01*
X30300Y273000D01*
X22300D01*
G37*
G36*
G01X18100Y276900D02*
X12500D01*
X12000Y277400D01*
Y284800D01*
X12300Y285100D01*
X17500D01*
X18300Y284300D01*
Y277100D01*
X18100Y276900D01*
G37*
G36*
G01X57700Y291272D02*
G03Y294528I-1900J1628D01*
G01Y328500D01*
X50800Y335400D01*
X14300D01*
X7700Y328800D01*
Y321377D01*
X7698Y321376D01*
Y302824D01*
X7700Y302823D01*
Y291400D01*
X6900Y290600D01*
X3900D01*
X3100Y291400D01*
Y350400D01*
X4000Y351300D01*
X60600D01*
X61500Y350400D01*
Y287900D01*
X60600Y287000D01*
X58500D01*
X57700Y287800D01*
Y291272D01*
G37*
G36*
G01X6415Y240253D02*
X7516Y241354D01*
Y241358D01*
X8514Y242354D01*
X8518D01*
X10136Y243975D01*
Y243977D01*
X10193Y244034D01*
Y256470D01*
X11108Y257385D01*
X15326D01*
X18438Y254273D01*
Y241248D01*
X13441Y236251D01*
X6894D01*
X6415Y236730D01*
Y240253D01*
G37*
G36*
G01X13497Y224595D02*
X6259D01*
X4818Y226036D01*
Y234004D01*
X5856Y235042D01*
X13997D01*
X20151Y241196D01*
Y250160D01*
X24066Y254075D01*
X31458D01*
X33787Y251746D01*
Y247091D01*
X31287Y244591D01*
X27749D01*
X24742Y241584D01*
Y238766D01*
X17427Y231451D01*
Y228525D01*
X13497Y224595D01*
G37*
G36*
G01X35954Y297822D02*
X29013D01*
X27825Y299010D01*
Y325601D01*
X30439Y328215D01*
X34703D01*
X36763Y326155D01*
Y298631D01*
X35954Y297822D01*
G37*
G36*
G01X95300Y10800D02*
X94340Y11760D01*
Y15382D01*
X94300Y15421D01*
Y17800D01*
X94700Y18200D01*
X97023D01*
X97950Y17273D01*
Y11150D01*
X97400Y10600D01*
Y4200D01*
X95300D01*
Y10800D01*
G37*
G36*
G01X127600Y12600D02*
X129900Y14900D01*
Y17400D01*
X131622Y19122D01*
X134878D01*
X136200Y17800D01*
Y16700D01*
X131650Y12150D01*
Y11350D01*
X130100Y9800D01*
Y4200D01*
X127600D01*
Y12600D01*
G37*
G36*
G01X110100Y4200D02*
X107600D01*
Y10560D01*
X106927Y11233D01*
X104917D01*
X104300Y11850D01*
Y18100D01*
X105000Y18800D01*
X109400D01*
X110100Y18100D01*
Y4200D01*
G37*
G36*
G01X112500D02*
Y18200D01*
X113000Y18700D01*
X118600D01*
X119400Y17900D01*
Y15155D01*
X119398Y15154D01*
Y14601D01*
X117300Y12502D01*
Y12500D01*
X115400Y10600D01*
Y4200D01*
X112500D01*
G37*
G36*
G01X204635Y-23377D02*
Y-787D01*
G03X201000Y3999I-4969J-1D01*
G01Y17000D01*
X206396Y22396D01*
X209139D01*
G02X209344Y21652I0J-400D01*
G03X214056I2356J-3952D01*
G02X214261Y22396I205J344D01*
G01X215903D01*
X218125Y24618D01*
Y26655D01*
X218456Y26986D01*
X224864D01*
X227986Y30108D01*
Y33066D01*
X227988Y33067D01*
Y33378D01*
X228002Y33392D01*
Y42524D01*
X228840Y43362D01*
Y64638D01*
X225398Y68080D01*
X224900D01*
Y92500D01*
X226900Y94500D01*
X228500D01*
X229676Y93324D01*
Y-22441D01*
G02X228740Y-23377I-936J0D01*
G01X204635D01*
G37*
G36*
G01X173500Y120500D02*
X173266Y120734D01*
Y131393D01*
X173625Y131752D01*
X191442D01*
X191447Y131747D01*
X211253D01*
X211500Y131500D01*
Y128122D01*
X211498Y128121D01*
Y127913D01*
X210587Y127002D01*
X203889D01*
X203585Y126698D01*
X203584D01*
X203583Y126696D01*
X203243D01*
X202486Y125940D01*
X197547D01*
X196708Y125100D01*
X187683D01*
X187542Y124958D01*
X180958D01*
X176500Y120500D01*
X173500D01*
G37*
G36*
G01X218100Y192800D02*
X217500Y193400D01*
Y194600D01*
X218000Y195100D01*
Y196535D01*
G03X218002Y196600I-1599J82D01*
G01Y197802D01*
X221200Y201000D01*
Y204400D01*
X221700Y204900D01*
X225193D01*
X225793Y204300D01*
Y195500D01*
X225488Y195195D01*
X224044D01*
X224036Y195196D01*
G03X223900Y195202I-139J-1596D01*
G01X222500D01*
G03X222120Y195156I1J-1602D01*
G01X222096Y195150D01*
X221650D01*
X219300Y192800D01*
X218100D01*
G37*
G36*
G01X207792Y226218D02*
G03Y221814I-42J-2202D01*
G02X208200Y221415I8J-400D01*
G01Y207598D01*
X203102Y202500D01*
X179510D01*
X176309Y205701D01*
Y220040D01*
X186233Y229964D01*
G03X191829Y231680I2350J2319D01*
G01X191841Y231741D01*
X194330Y234230D01*
Y252611D01*
X191326Y255615D01*
G02X191609Y256298I283J283D01*
G01X196305D01*
G03X197162Y255717I4094J5116D01*
G02X197123Y255002I-197J-348D01*
G03X200832Y254229I1303J-3034D01*
G02X201081Y254901I291J274D01*
G03X193852Y261053I-687J6516D01*
G02X193453Y260630I-399J-23D01*
G01X191587D01*
G02X191188Y261053I0J400D01*
G03X179648Y257181I-6542J364D01*
G02X179343Y256522I-305J-259D01*
G01X178230D01*
X176691Y258061D01*
Y266548D01*
X181043Y270900D01*
X196457D01*
X199550Y273993D01*
Y284910D01*
X199903Y285263D01*
X207882D01*
X208257Y284888D01*
Y272785D01*
X215570Y265472D01*
Y234776D01*
X215033Y234239D01*
G03X213899Y233105I883J-2017D01*
G01X212324Y231530D01*
X211080D01*
G03X208280Y228161I-1574J-1540D01*
G02X208340Y227546I-223J-332D01*
G01X208200Y227406D01*
Y226617D01*
G02X207792Y226218I-400J1D01*
G37*
G36*
G01X177941Y284800D02*
G03X177857Y284798I-4J-1601D01*
G01X177540D01*
X177137Y285201D01*
Y293635D01*
X177489Y293987D01*
X199292D01*
X200861Y292418D01*
Y287709D01*
X200037Y286885D01*
X182847D01*
X180760Y284798D01*
X179625D01*
G03X179541Y284800I-80J-1599D01*
G01X177941D01*
G37*
G36*
G01X209468Y284148D02*
G03X209467Y284210I-1601J5D01*
G01Y285091D01*
X210197Y285821D01*
X213057D01*
X218896Y279982D01*
Y269887D01*
X217753Y268744D01*
X214267D01*
X209467Y273544D01*
Y282686D01*
G03X209468Y282748I-1600J57D01*
G01Y284148D01*
G37*
G36*
G01X195806Y272255D02*
X184236D01*
X182587Y273904D01*
Y284926D01*
X183296Y285635D01*
X197403D01*
X198174Y284864D01*
Y274623D01*
X195806Y272255D01*
G37*
G36*
G01X191258Y244937D02*
X178863D01*
X163700Y260100D01*
Y272548D01*
X174749Y283597D01*
X180915D01*
X181386Y283126D01*
Y273582D01*
X175298Y267494D01*
Y257439D01*
X178969Y253768D01*
X190673D01*
X192801Y251640D01*
Y246480D01*
X191258Y244937D01*
G37*
G36*
G01X195000Y298200D02*
X189300D01*
X187970Y299530D01*
Y326130D01*
X189730Y327890D01*
X195590D01*
X197360Y326120D01*
Y300560D01*
X195000Y298200D01*
G37*
G36*
G01X228300Y320900D02*
X216200D01*
X212600Y324500D01*
Y332900D01*
X210000Y335500D01*
X172300D01*
X171200Y336600D01*
Y350500D01*
X172000Y351300D01*
X228800D01*
X229600Y350500D01*
Y322200D01*
X228300Y320900D01*
G37*
G36*
G01X225400Y304700D02*
X225200Y304500D01*
X219600D01*
X219100Y305000D01*
Y312400D01*
X219400Y312700D01*
X224900D01*
X225400Y312200D01*
Y304700D01*
G37*
%LPC*%
G75*
G36*
G01X188735Y216142D02*
X196305D01*
G02X197162Y216723I4094J-5116D01*
G03X197123Y217438I-197J348D01*
G02X200832Y218211I1303J3034D01*
G03X201081Y217539I291J-274D01*
G02X193852Y211387I-687J-6516D01*
G03X193453Y211810I-399J23D01*
G01X191587D01*
G03X191188Y211387I0J-400D01*
G02X188735Y216142I-6542J-365D01*
G37*
G54D80*
X193354Y290524D03*
X188754D03*
X193354Y281524D03*
X188754D03*
G54D78*
X12000Y342400D03*
X180200Y342500D03*
G54D76*
X38189Y228346D03*
X28346Y250000D03*
X188583Y222440D03*
X198426Y244094D03*
Y228346D03*
Y236220D03*
X188583Y250000D03*
G54D79*
X32283Y322835D03*
Y303149D03*
X192520Y322835D03*
Y303149D03*
G54D74*
X13800Y60400D03*
X218800Y337200D03*
G54D77*
X34800Y282900D03*
Y285100D03*
X5097Y256779D03*
Y253379D03*
Y252027D03*
Y248627D03*
X5093Y247266D03*
Y243866D03*
X29200Y282900D03*
X8353Y237397D03*
X13853Y241897D03*
X14093Y243866D03*
Y247266D03*
X14097Y248627D03*
Y252027D03*
Y253379D03*
X13853Y229797D03*
X8353D03*
X220478Y24805D03*
X220200Y196200D03*
X222100Y197400D03*
X224300D03*
X220200Y198400D03*
X206067Y282348D03*
X197354Y290524D03*
X184754D03*
X211667Y284548D03*
Y282348D03*
X197354Y281524D03*
X184754D03*
X188570Y279231D03*
X184070D03*
X188570Y273731D03*
X176470Y279231D03*
Y273731D03*
G54D75*
X116339Y78740D03*
%LPD*%
G75*
G54D10*
G01X67560Y25750D02*
X70360D01*
G01X69446Y48262D02*
X68208Y49500D01*
X64450D01*
G01X56150Y38600D02*
Y41350D01*
X55500Y42000D01*
G01X37450Y48600D02*
X35744Y50306D01*
Y51944D01*
G01X56750Y32300D02*
Y33750D01*
X56600Y33900D01*
Y34550D01*
X57450Y35400D01*
G01X32100Y114900D02*
X31500Y114300D01*
Y112222D01*
G01X20200Y116600D02*
X19100D01*
X17700Y115200D01*
Y112250D01*
G01X22800Y112600D02*
X25600D01*
X27948Y110252D01*
X29058D01*
G01X17700Y89400D02*
X16705D01*
X15700Y88395D01*
Y86550D01*
X15900Y86350D01*
G01D02*
X17450D01*
X19460Y84340D01*
X21600D01*
G01X48300Y172050D02*
Y169700D01*
X47300Y168700D01*
G01X15007Y163581D02*
X14569Y164019D01*
Y167477D01*
G01X7985Y222237D02*
Y221274D01*
X6220Y219509D01*
G01X114900Y39900D02*
X114100D01*
X111958Y37758D01*
Y35685D01*
G01X212287Y39469D02*
X211318Y38500D01*
X207150D01*
G01X161350Y48200D02*
Y51450D01*
X161300Y51500D01*
G01X210276Y122000D02*
X209976Y121700D01*
Y119370D01*
G01X204818Y118400D02*
X204900Y118318D01*
Y118300D01*
X205800Y117400D01*
X207534D01*
G01X198100Y104000D02*
X199160Y102940D01*
X203050D01*
G01X215400Y88900D02*
X216080Y89580D01*
X220600D01*
G01X174600Y86980D02*
Y83340D01*
G01X215821Y221230D02*
Y218363D01*
X214119Y216661D01*
X-18898Y16741D03*
X-17506Y723144D03*
X41752Y5118D03*
X13800Y60400D03*
X114497Y137176D03*
X115583Y329366D03*
X114497Y525759D03*
X115583Y717948D03*
X190926Y5118D03*
X218800Y337200D03*
X365520Y-1413D03*
X366606Y190776D03*
X365520Y387169D03*
X366606Y579359D03*
X494816Y713716D03*
G54D20*
X25600Y70800D03*
X36931Y66704D03*
X56700Y32300D03*
X41700Y118500D03*
X39200Y91400D03*
X48200Y187610D03*
Y195610D03*
X50862Y154167D03*
X111600Y24900D03*
X133400Y24000D03*
X79100Y47000D03*
X180700Y70200D03*
X174300Y48800D03*
X220682Y49139D03*
X192200Y90000D03*
X218300Y119000D03*
X219100Y181300D03*
Y197300D03*
X217800Y206700D03*
X210567Y283448D03*
G54D11*
X-5631Y5915D03*
X-4866Y709193D03*
X12000Y342400D03*
X211700Y17700D03*
X180200Y342500D03*
X489553Y2518D03*
G54D21*
X22200Y70800D03*
X33531Y66704D03*
X53300Y32300D03*
X38300Y118500D03*
X35800Y91400D03*
X44800Y187610D03*
Y195610D03*
X47462Y154167D03*
X108200Y24900D03*
X130000Y24000D03*
X75700Y47000D03*
X177300Y70200D03*
X170900Y48800D03*
X217282Y49139D03*
X188800Y90000D03*
X214900Y119000D03*
X215700Y181300D03*
Y197300D03*
X214400Y206700D03*
X207167Y283448D03*
G54D30*
X17700Y106250D03*
Y112250D03*
X15300Y288650D03*
Y282650D03*
X222189Y316231D03*
Y310231D03*
G54D12*
X23760Y-1772D03*
X208918D03*
G54D22*
X41000Y48600D03*
X40200Y58800D03*
X59700Y38600D03*
X164900Y48200D03*
X214500Y201900D03*
G54D40*
X47933Y128937D03*
X16633D03*
X47933Y146653D03*
X16633D03*
X208170Y128937D03*
X176870D03*
X208170Y146653D03*
X176870D03*
G54D31*
X31500Y112222D03*
Y110252D03*
Y108282D03*
X29058D03*
Y110252D03*
Y112222D03*
X209976Y119370D03*
Y117400D03*
Y115430D03*
X207534D03*
Y117400D03*
Y119370D03*
G54D13*
X6000Y-17500D03*
X16090Y-6960D03*
Y-3360D03*
X4100Y12300D03*
X4300Y38700D03*
X21000Y53500D03*
X4629Y64843D03*
X16090Y240D03*
X63938Y11580D03*
X16090Y3840D03*
X70600Y122500D03*
X65600Y128100D03*
X42600Y129000D03*
X22383Y128937D03*
X20200Y116600D03*
X6220Y219509D03*
X51500Y187600D03*
X51400Y195600D03*
X56755Y199384D03*
X26700Y189160D03*
X22598Y150420D03*
X51076Y202657D03*
X51500Y191500D03*
X44100Y154167D03*
X56400Y158800D03*
X5244Y259114D03*
X4333Y242011D03*
X55200Y285022D03*
X98000Y68200D03*
X112900Y51800D03*
X102000Y62400D03*
X134800Y60300D03*
X135800Y70800D03*
X140100Y14000D03*
X78838Y11602D03*
X124300Y99500D03*
X97600Y92200D03*
X94193Y99637D03*
X81634Y111544D03*
X76100Y117800D03*
X87600Y106400D03*
X101600Y99700D03*
X135900Y99400D03*
X146700Y108400D03*
X217340Y-3360D03*
Y-6960D03*
Y240D03*
Y3840D03*
X168858Y12000D03*
X212287Y39469D03*
X154700Y116500D03*
X190700Y127400D03*
X202783Y128937D03*
X215400Y88900D03*
X186100Y186500D03*
X205848Y199637D03*
X219150Y178000D03*
X222450Y199500D03*
X218700Y193900D03*
X222800Y182000D03*
X199600Y156500D03*
X178747Y288699D03*
X182347Y292152D03*
X199557Y292020D03*
X199521Y288390D03*
X220678Y284412D03*
G54D32*
X33700Y118100D03*
X12100Y81300D03*
X28200Y117900D03*
X7200Y199300D03*
X9050Y191800D03*
X48300Y172100D03*
X54492Y181924D03*
X76500Y51200D03*
X80600D03*
X79200Y70100D03*
Y62600D03*
X79604Y80369D03*
X188250Y59096D03*
X222500Y38800D03*
X219378Y25905D03*
X205500Y48800D03*
X215300Y53200D03*
X201500Y48800D03*
X218832Y124859D03*
X168936Y76013D03*
X205500Y172700D03*
X209900D03*
G54D23*
X37400Y48600D03*
X36600Y58800D03*
X56100Y38600D03*
X161300Y48200D03*
X210900Y201900D03*
G54D14*
X68819Y6299D03*
X63819D03*
X58819D03*
X53819D03*
X143839D03*
X138839D03*
X133839D03*
X128839D03*
X123839D03*
X118839D03*
X113839D03*
X108839D03*
X83819D03*
X78819D03*
X73819D03*
X178839D03*
X173839D03*
X168839D03*
X163839D03*
X158839D03*
X153839D03*
X148839D03*
G54D41*
X16538Y173177D03*
X12600D03*
X16538Y167477D03*
X14569D03*
X12600D03*
X217790Y221230D03*
X215821D03*
X213852D03*
X217790Y226930D03*
X213852D03*
G54D50*
X16798Y154767D03*
G54D33*
X33700Y121500D03*
X12100Y84700D03*
X28200Y121300D03*
X7200Y202700D03*
X9050Y195200D03*
X48300Y175500D03*
X54492Y185324D03*
X76500Y54600D03*
X80600D03*
X79200Y66000D03*
Y73500D03*
X79604Y83769D03*
X188250Y62496D03*
X222500Y42200D03*
X219378Y29305D03*
X205500Y52200D03*
X215300Y56600D03*
X201500Y52200D03*
X218832Y128259D03*
X168936Y79413D03*
X205500Y176100D03*
X209900D03*
G54D15*
X69500Y65420D03*
Y67980D03*
Y70540D03*
X47300D03*
Y67980D03*
Y65420D03*
X69500Y73100D03*
Y75660D03*
Y78220D03*
Y80780D03*
Y83340D03*
Y85900D03*
Y88460D03*
Y91020D03*
Y93580D03*
X47300D03*
Y91020D03*
Y88460D03*
Y85900D03*
Y83340D03*
Y80780D03*
Y78220D03*
Y75660D03*
Y73100D03*
X34400Y84340D03*
Y81780D03*
Y79220D03*
Y76660D03*
X21600D03*
Y79220D03*
Y81780D03*
Y84340D03*
X37190Y196840D03*
Y194280D03*
Y191720D03*
Y189160D03*
X21010D03*
Y191720D03*
Y194280D03*
Y196840D03*
X220600Y61420D03*
Y63980D03*
Y66540D03*
Y69100D03*
Y71660D03*
X198400D03*
Y69100D03*
Y66540D03*
Y63980D03*
Y61420D03*
X220600Y74220D03*
Y76780D03*
Y79340D03*
Y81900D03*
Y84460D03*
Y87020D03*
Y89580D03*
X198400D03*
Y87020D03*
Y84460D03*
Y81900D03*
Y79340D03*
Y76780D03*
Y74220D03*
X187400Y83340D03*
Y80780D03*
Y78220D03*
Y75660D03*
X174600D03*
Y78220D03*
Y80780D03*
Y83340D03*
X207590Y195940D03*
Y193380D03*
Y190820D03*
Y188260D03*
X191410D03*
Y190820D03*
Y193380D03*
Y195940D03*
G54D24*
X52600Y27100D03*
X104300Y28500D03*
X197760Y56827D03*
X215800Y107610D03*
X192724Y80830D03*
G54D51*
X7985Y222487D03*
G54D60*
X215520Y140700D03*
G54D42*
X37283Y173228D03*
X27283D03*
X193583D03*
X183583D03*
G54D70*
G01X51750Y107940D02*
X47300D01*
G01X34292Y103542D02*
Y106026D01*
X34900Y106634D01*
Y106742D01*
G01X58250Y113060D02*
X57340D01*
X53750Y116650D01*
Y118300D01*
G01X24409Y204271D02*
Y211023D01*
G01X17657D02*
X24409D01*
G01D02*
X31161D01*
G01X33405D02*
X40157D01*
G01X35183Y206049D02*
X40157Y211023D01*
G01X24409Y261417D02*
Y268169D01*
G01X17657Y261417D02*
X24409D01*
G01D02*
X31161D01*
G01X40157D02*
Y268169D01*
G01X33405Y261417D02*
X40157D01*
G01D02*
X46909D01*
G01X79604Y83819D02*
Y86869D01*
G01X200394Y204271D02*
Y211023D01*
G01X193642D02*
X200394D01*
G01D02*
X207146D01*
G01X184646Y204271D02*
Y211023D01*
G01X177894D02*
X184646D01*
G01D02*
X191398D01*
G01X184646Y261417D02*
Y268169D01*
G01X177894Y261417D02*
X184646D01*
G01D02*
X191398D01*
G01X200394D02*
Y268169D01*
G01X193642Y261417D02*
X200394D01*
G01D02*
X207146D01*
G54D43*
X33809Y159738D03*
X6797Y255079D03*
Y250327D03*
X6793Y245566D03*
X188783Y156500D03*
G54D16*
X47060Y32450D03*
X44500D03*
X41940D03*
Y25950D03*
X47060D03*
X62440Y25750D03*
X65000D03*
X67560D03*
Y32250D03*
X62440D03*
G54D52*
X25000Y277000D03*
X36000D03*
X213790Y276128D03*
X202790D03*
G54D61*
X215520Y146300D03*
G54D25*
X52600Y23500D03*
X104300Y24900D03*
X197760Y53227D03*
X215800Y104010D03*
X192724Y77230D03*
G54D34*
X12100Y77200D03*
X23300Y109200D03*
X52400Y175500D03*
X50272Y288472D03*
X98071Y51625D03*
X75604Y83769D03*
X219500Y56600D03*
X192500Y70200D03*
X218300Y39200D03*
X215378Y29305D03*
X209522Y52212D03*
X180800Y108300D03*
X215516Y135785D03*
X223200Y188750D03*
Y196300D03*
X220723Y291345D03*
G54D71*
G01X41000Y36900D02*
X41940Y35960D01*
Y32450D01*
G01X52600Y27050D02*
X50250D01*
X49150Y25950D01*
X47060D01*
G01X59650Y38600D02*
X62000D01*
X63300Y37300D01*
G01X62440Y32250D02*
Y32860D01*
X59850Y35450D01*
Y38400D01*
X59650Y38600D01*
G01X163452Y35522D02*
Y32350D01*
G01X169750Y62500D02*
X170750Y61500D01*
Y59560D01*
G01X176300Y40450D02*
X176108Y40642D01*
X169952D01*
G01X164250Y54440D02*
Y52450D01*
X164850Y51850D01*
Y48200D01*
G01X209550Y108060D02*
X215300D01*
X215800Y107560D01*
G54D26*
X20300Y26600D03*
G54D53*
X11103Y232047D03*
Y239647D03*
G54D62*
X178720Y276481D03*
X186320D03*
G54D17*
X48150Y45565D03*
Y47530D03*
Y49500D03*
Y51470D03*
Y53435D03*
X64450D03*
Y51470D03*
Y49500D03*
Y47530D03*
Y45565D03*
X190850Y34565D03*
Y36530D03*
Y38500D03*
Y40470D03*
Y42435D03*
X207150D03*
Y40470D03*
Y38500D03*
Y36530D03*
Y34565D03*
G54D35*
X12100Y73800D03*
X23300Y105800D03*
X52400Y172100D03*
X50272Y285072D03*
X98071Y48225D03*
X75604Y80369D03*
X219500Y53200D03*
X192500Y66800D03*
X218300Y35800D03*
X215378Y25905D03*
X209522Y48812D03*
X180800Y104900D03*
X215516Y132385D03*
X223200Y185350D03*
Y192900D03*
X220723Y287945D03*
G54D44*
X39409Y159738D03*
X12397Y255079D03*
Y250327D03*
X12393Y245566D03*
X194383Y156500D03*
G54D72*
G01X-322688Y-405500D02*
X-321814Y-404625D01*
X-321159Y-403167D01*
X-320722Y-401124D01*
X-321159Y-399375D01*
X-322032Y-398208D01*
X-323561Y-397333D01*
X-329456D01*
Y-414833D01*
X-322251D01*
X-320722Y-413667D01*
X-319849Y-411916D01*
X-319412Y-409875D01*
X-319849Y-407833D01*
X-321159Y-406083D01*
X-322688Y-405500D01*
X-329456D01*
G01X-309991Y-414833D02*
Y-403167D01*
G01Y-405500D02*
X-308899Y-404333D01*
X-307807Y-403458D01*
X-306279Y-403167D01*
X-305188Y-403458D01*
X-303877Y-404333D01*
G01X-294019Y-420083D02*
X-292709Y-420666D01*
X-290962Y-420083D01*
X-289871Y-418917D01*
X-288997Y-417458D01*
X-287688Y-412792D01*
X-284849Y-403167D01*
G01X-291836D02*
X-287688Y-412792D01*
G01X-268441Y-404625D02*
X-269969Y-403458D01*
X-271279Y-403167D01*
X-273026Y-403750D01*
X-274336Y-404916D01*
X-275209Y-406958D01*
X-275428Y-409000D01*
X-275209Y-411042D01*
X-274336Y-412792D01*
X-273026Y-414250D01*
X-271279Y-414833D01*
X-269751Y-414250D01*
X-268441Y-413083D01*
G01X-257709Y-406958D02*
X-250722D01*
X-251377Y-404916D01*
X-252469Y-403750D01*
X-253997Y-403167D01*
X-255526Y-403458D01*
X-256836Y-404333D01*
X-257709Y-406375D01*
X-258146Y-408125D01*
Y-409875D01*
X-257709Y-411625D01*
X-256617Y-413375D01*
X-255307Y-414541D01*
X-253779Y-414833D01*
X-252251Y-414250D01*
X-250722Y-412500D01*
G01X-214631Y-398792D02*
X-215941Y-397916D01*
X-217469Y-397333D01*
X-219216D01*
X-221181Y-398208D01*
X-222709Y-399666D01*
X-223801Y-401417D01*
X-224674Y-404333D01*
X-224893Y-406958D01*
X-224456Y-409583D01*
X-223801Y-411333D01*
X-222491Y-413083D01*
X-220962Y-414250D01*
X-219434Y-414833D01*
X-217906D01*
X-216377Y-414250D01*
X-215067Y-413375D01*
X-213975Y-412209D01*
G01X-198004Y-414833D02*
Y-403167D01*
G01Y-405208D02*
X-198877Y-404042D01*
X-200188Y-403458D01*
X-201716Y-403167D01*
X-203244Y-403750D01*
X-204554Y-404916D01*
X-205428Y-406666D01*
X-205864Y-409000D01*
X-205428Y-411333D01*
X-204554Y-413083D01*
X-203244Y-414250D01*
X-201716Y-414833D01*
X-200188Y-414541D01*
X-198877Y-413667D01*
X-198004Y-412500D01*
G01X-188146Y-414833D02*
Y-403167D01*
G01Y-406083D02*
X-187272Y-404625D01*
X-185962Y-403458D01*
X-184216Y-403167D01*
X-182688Y-403458D01*
X-181377Y-404625D01*
X-180722Y-406666D01*
Y-414833D01*
G01X-171519Y-420083D02*
X-170209Y-420666D01*
X-168462Y-420083D01*
X-167371Y-418917D01*
X-166497Y-417458D01*
X-165188Y-412792D01*
X-162349Y-403167D01*
G01X-169336D02*
X-165188Y-412792D01*
G01X-149434Y-414833D02*
X-150744Y-414541D01*
X-152054Y-413375D01*
X-152928Y-411333D01*
X-153364Y-409000D01*
X-152928Y-406666D01*
X-152054Y-404625D01*
X-150744Y-403458D01*
X-149434Y-403167D01*
X-148124Y-403458D01*
X-146814Y-404625D01*
X-145941Y-406666D01*
X-145722Y-409000D01*
X-145941Y-411333D01*
X-146814Y-413375D01*
X-148124Y-414541D01*
X-149434Y-414833D01*
G01X-135646D02*
Y-403167D01*
G01Y-406083D02*
X-134772Y-404625D01*
X-133462Y-403458D01*
X-131716Y-403167D01*
X-130188Y-403458D01*
X-128877Y-404625D01*
X-128222Y-406666D01*
Y-414833D01*
G01X-101082D02*
Y-397333D01*
X-92786D01*
G01X-95842Y-405791D02*
X-101082D01*
G01X-82491Y-414833D02*
Y-403167D01*
G01Y-405500D02*
X-81399Y-404333D01*
X-80307Y-403458D01*
X-78779Y-403167D01*
X-77688Y-403458D01*
X-76377Y-404333D01*
G01X-61934Y-414833D02*
X-63244Y-414541D01*
X-64554Y-413375D01*
X-65428Y-411333D01*
X-65864Y-409000D01*
X-65428Y-406666D01*
X-64554Y-404625D01*
X-63244Y-403458D01*
X-61934Y-403167D01*
X-60624Y-403458D01*
X-59314Y-404625D01*
X-58441Y-406666D01*
X-58222Y-409000D01*
X-58441Y-411333D01*
X-59314Y-413375D01*
X-60624Y-414541D01*
X-61934Y-414833D01*
G01X-48146D02*
Y-403167D01*
G01Y-406083D02*
X-47272Y-404625D01*
X-45962Y-403458D01*
X-44216Y-403167D01*
X-42688Y-403458D01*
X-41377Y-404625D01*
X-40722Y-406666D01*
Y-414833D01*
G01X-26934Y-397333D02*
Y-414833D01*
G01X-29991Y-403167D02*
X-23877D01*
G01X3699Y-414833D02*
Y-397333D01*
X8939D01*
X10686Y-398208D01*
X11996Y-400250D01*
X12433Y-402583D01*
X11996Y-404916D01*
X10904Y-406666D01*
X8939Y-407542D01*
X3699D01*
G01X29496Y-414833D02*
Y-403167D01*
G01Y-405208D02*
X28623Y-404042D01*
X27312Y-403458D01*
X25784Y-403167D01*
X24256Y-403750D01*
X22946Y-404916D01*
X22072Y-406666D01*
X21636Y-409000D01*
X22072Y-411333D01*
X22946Y-413083D01*
X24256Y-414250D01*
X25784Y-414833D01*
X27312Y-414541D01*
X28623Y-413667D01*
X29496Y-412500D01*
G01X39354Y-414833D02*
Y-403167D01*
G01Y-406083D02*
X40228Y-404625D01*
X41538Y-403458D01*
X43284Y-403167D01*
X44812Y-403458D01*
X46123Y-404625D01*
X46778Y-406666D01*
Y-414833D01*
G01X57291Y-406958D02*
X64278D01*
X63623Y-404916D01*
X62531Y-403750D01*
X61003Y-403167D01*
X59474Y-403458D01*
X58164Y-404333D01*
X57291Y-406375D01*
X56854Y-408125D01*
Y-409875D01*
X57291Y-411625D01*
X58383Y-413375D01*
X59693Y-414541D01*
X61221Y-414833D01*
X62749Y-414250D01*
X64278Y-412500D01*
G01X78066Y-414833D02*
Y-397333D01*
G01X114812Y-405500D02*
X115686Y-404625D01*
X116341Y-403167D01*
X116778Y-401124D01*
X116341Y-399375D01*
X115468Y-398208D01*
X113939Y-397333D01*
X108044D01*
Y-414833D01*
X115249D01*
X116778Y-413667D01*
X117651Y-411916D01*
X118088Y-409875D01*
X117651Y-407833D01*
X116341Y-406083D01*
X114812Y-405500D01*
X108044D01*
G01X130566Y-414833D02*
X129256Y-414541D01*
X127946Y-413375D01*
X127072Y-411333D01*
X126636Y-409000D01*
X127072Y-406666D01*
X127946Y-404625D01*
X129256Y-403458D01*
X130566Y-403167D01*
X131876Y-403458D01*
X133186Y-404625D01*
X134059Y-406666D01*
X134278Y-409000D01*
X134059Y-411333D01*
X133186Y-413375D01*
X131876Y-414541D01*
X130566Y-414833D01*
G01X151996D02*
Y-403167D01*
G01Y-405208D02*
X151123Y-404042D01*
X149812Y-403458D01*
X148284Y-403167D01*
X146756Y-403750D01*
X145446Y-404916D01*
X144572Y-406666D01*
X144136Y-409000D01*
X144572Y-411333D01*
X145446Y-413083D01*
X146756Y-414250D01*
X148284Y-414833D01*
X149812Y-414541D01*
X151123Y-413667D01*
X151996Y-412500D01*
G01X162509Y-414833D02*
Y-403167D01*
G01Y-405500D02*
X163601Y-404333D01*
X164693Y-403458D01*
X166221Y-403167D01*
X167312Y-403458D01*
X168623Y-404333D01*
G01X186996Y-397333D02*
Y-414833D01*
G01Y-412209D02*
X186123Y-413667D01*
X184812Y-414541D01*
X183284Y-414833D01*
X181538Y-414250D01*
X180228Y-412792D01*
X179354Y-411042D01*
X179136Y-409000D01*
X179354Y-406958D01*
X180228Y-405208D01*
X181538Y-403750D01*
X183284Y-403167D01*
X184812Y-403458D01*
X185904Y-404042D01*
X186996Y-405208D01*
G01X-111361Y-369833D02*
Y-352333D01*
X-105684Y-366916D01*
X-100007Y-352333D01*
Y-369833D01*
G01X-88184D02*
X-89494Y-369541D01*
X-90804Y-368375D01*
X-91678Y-366333D01*
X-92114Y-364000D01*
X-91678Y-361666D01*
X-90804Y-359625D01*
X-89494Y-358458D01*
X-88184Y-358167D01*
X-86874Y-358458D01*
X-85564Y-359625D01*
X-84691Y-361666D01*
X-84472Y-364000D01*
X-84691Y-366333D01*
X-85564Y-368375D01*
X-86874Y-369541D01*
X-88184Y-369833D01*
G01X-66754Y-352333D02*
Y-369833D01*
G01Y-367209D02*
X-67627Y-368667D01*
X-68938Y-369541D01*
X-70466Y-369833D01*
X-72212Y-369250D01*
X-73522Y-367792D01*
X-74396Y-366042D01*
X-74614Y-364000D01*
X-74396Y-361958D01*
X-73522Y-360208D01*
X-72212Y-358750D01*
X-70466Y-358167D01*
X-68938Y-358458D01*
X-67846Y-359042D01*
X-66754Y-360208D01*
G01X-56459Y-361958D02*
X-49472D01*
X-50127Y-359916D01*
X-51219Y-358750D01*
X-52747Y-358167D01*
X-54276Y-358458D01*
X-55586Y-359333D01*
X-56459Y-361375D01*
X-56896Y-363125D01*
Y-364875D01*
X-56459Y-366625D01*
X-55367Y-368375D01*
X-54057Y-369541D01*
X-52529Y-369833D01*
X-51001Y-369250D01*
X-49472Y-367500D01*
G01X-35684Y-369833D02*
Y-352333D01*
G01X244916Y-414833D02*
Y-397333D01*
X242296Y-400833D01*
G01Y-414833D02*
X247536D01*
G01X258268Y-407542D02*
X259796Y-405500D01*
X261106Y-404333D01*
X262853Y-403750D01*
X264381Y-404333D01*
X265473Y-405500D01*
X266346Y-407250D01*
X266564Y-409291D01*
X266346Y-411042D01*
X265473Y-412792D01*
X264162Y-414250D01*
X262634Y-414833D01*
X260888Y-414250D01*
X259359Y-412500D01*
X258486Y-409875D01*
X258268Y-406958D01*
X258704Y-403167D01*
X259359Y-401124D01*
X260451Y-399083D01*
X261979Y-397625D01*
X263508Y-397333D01*
X265036Y-397916D01*
X266128Y-399375D01*
G01X275113Y-411333D02*
X276422Y-413375D01*
X278169Y-414541D01*
X280134Y-414833D01*
X281881Y-414541D01*
X283628Y-413083D01*
X284719Y-411333D01*
X284938Y-409583D01*
X284501Y-407542D01*
X282973Y-406083D01*
X281444Y-405500D01*
X279479D01*
G01X281444D02*
X282754Y-404625D01*
X283846Y-403167D01*
X284283Y-401417D01*
X283846Y-399666D01*
X282754Y-398208D01*
X280789Y-397333D01*
X278824Y-397625D01*
X276859Y-398792D01*
G01X293268Y-407542D02*
X294796Y-405500D01*
X296106Y-404333D01*
X297853Y-403750D01*
X299381Y-404333D01*
X300473Y-405500D01*
X301346Y-407250D01*
X301564Y-409291D01*
X301346Y-411042D01*
X300473Y-412792D01*
X299162Y-414250D01*
X297634Y-414833D01*
X295888Y-414250D01*
X294359Y-412500D01*
X293486Y-409875D01*
X293268Y-406958D01*
X293704Y-403167D01*
X294359Y-401124D01*
X295451Y-399083D01*
X296979Y-397625D01*
X298508Y-397333D01*
X300036Y-397916D01*
X301128Y-399375D01*
G01X311204Y-412792D02*
X312733Y-414250D01*
X314479Y-414833D01*
X316226Y-414250D01*
X317754Y-412500D01*
X318846Y-409875D01*
X319283Y-407250D01*
Y-404042D01*
X318846Y-401417D01*
X317754Y-399083D01*
X316444Y-397916D01*
X314916Y-397333D01*
X313169Y-397916D01*
X311859Y-399083D01*
X310986Y-400833D01*
X310549Y-403167D01*
X310986Y-405208D01*
X312078Y-407250D01*
X313388Y-408417D01*
X314916Y-408708D01*
X316662Y-408125D01*
X317973Y-406666D01*
X319283Y-404042D01*
G01X231799Y-369833D02*
Y-352333D01*
X237039D01*
X238786Y-353208D01*
X240096Y-355250D01*
X240533Y-357583D01*
X240096Y-359916D01*
X239004Y-361666D01*
X237039Y-362542D01*
X231799D01*
G01X258469Y-353792D02*
X257159Y-352916D01*
X255631Y-352333D01*
X253884D01*
X251919Y-353208D01*
X250391Y-354666D01*
X249299Y-356417D01*
X248426Y-359333D01*
X248207Y-361958D01*
X248644Y-364583D01*
X249299Y-366333D01*
X250609Y-368083D01*
X252138Y-369250D01*
X253666Y-369833D01*
X255194D01*
X256723Y-369250D01*
X258033Y-368375D01*
X259125Y-367209D01*
G01X272912Y-360500D02*
X273786Y-359625D01*
X274441Y-358167D01*
X274878Y-356124D01*
X274441Y-354375D01*
X273568Y-353208D01*
X272039Y-352333D01*
X266144D01*
Y-369833D01*
X273349D01*
X274878Y-368667D01*
X275751Y-366916D01*
X276188Y-364875D01*
X275751Y-362833D01*
X274441Y-361083D01*
X272912Y-360500D01*
X266144D01*
G01X282116Y-375666D02*
X295216D01*
G01X301144Y-369833D02*
Y-352333D01*
X311188Y-369833D01*
Y-352333D01*
G01X323666Y-369833D02*
X321919Y-369541D01*
X320391Y-368375D01*
X319081Y-366625D01*
X318207Y-364583D01*
X317771Y-362250D01*
Y-359916D01*
X318207Y-357583D01*
X319081Y-355541D01*
X320391Y-353792D01*
X321919Y-352625D01*
X323666Y-352333D01*
X325412Y-352625D01*
X326941Y-353792D01*
X328251Y-355541D01*
X329125Y-357583D01*
X329561Y-359916D01*
Y-362250D01*
X329125Y-364583D01*
X328251Y-366625D01*
X326941Y-368375D01*
X325412Y-369541D01*
X323666Y-369833D01*
G01X374507Y-352333D02*
X379966Y-369833D01*
X385425Y-352333D01*
G01X401833Y-369833D02*
X393099D01*
Y-352333D01*
X401833D01*
G01X398339Y-360791D02*
X393099D01*
G01X410599Y-369833D02*
Y-352333D01*
X416058D01*
X417804Y-353208D01*
X418896Y-354375D01*
X419333Y-356708D01*
X418896Y-359042D01*
X417586Y-360500D01*
X416058Y-361375D01*
X410599D01*
G01X416058D02*
X419333Y-369833D01*
G01X432466Y-370416D02*
X432029Y-370125D01*
Y-369541D01*
X432466Y-369250D01*
X432903Y-369541D01*
Y-370125D01*
X432466Y-370416D01*
G01X392881Y-412500D02*
X394628Y-413958D01*
X396593Y-414833D01*
X398339D01*
X400086Y-413958D01*
X401396Y-412500D01*
X402051Y-410458D01*
X401614Y-408417D01*
X400523Y-406666D01*
X398558Y-405500D01*
X395938Y-404916D01*
X394409Y-403750D01*
X393754Y-401708D01*
X394191Y-399666D01*
X395283Y-398208D01*
X396811Y-397333D01*
X398339D01*
X399868Y-397916D01*
X401178Y-399375D01*
G01X410163Y-414833D02*
Y-397333D01*
X414529D01*
X416276Y-398208D01*
X417586Y-399375D01*
X418678Y-401124D01*
X419551Y-403167D01*
X419769Y-406083D01*
X419551Y-409000D01*
X418678Y-411042D01*
X417586Y-412792D01*
X416276Y-413958D01*
X414529Y-414833D01*
X410163D01*
G01X508049Y-352333D02*
Y-369833D01*
X516783D01*
G01X533846D02*
Y-358167D01*
G01Y-360208D02*
X532973Y-359042D01*
X531662Y-358458D01*
X530134Y-358167D01*
X528606Y-358750D01*
X527296Y-359916D01*
X526422Y-361666D01*
X525986Y-364000D01*
X526422Y-366333D01*
X527296Y-368083D01*
X528606Y-369250D01*
X530134Y-369833D01*
X531662Y-369541D01*
X532973Y-368667D01*
X533846Y-367500D01*
G01X542831Y-375083D02*
X544141Y-375666D01*
X545888Y-375083D01*
X546979Y-373917D01*
X547853Y-372458D01*
X549162Y-367792D01*
X552001Y-358167D01*
G01X545014D02*
X549162Y-367792D01*
G01X561641Y-361958D02*
X568628D01*
X567973Y-359916D01*
X566881Y-358750D01*
X565353Y-358167D01*
X563824Y-358458D01*
X562514Y-359333D01*
X561641Y-361375D01*
X561204Y-363125D01*
Y-364875D01*
X561641Y-366625D01*
X562733Y-368375D01*
X564043Y-369541D01*
X565571Y-369833D01*
X567099Y-369250D01*
X568628Y-367500D01*
G01X579359Y-369833D02*
Y-358167D01*
G01Y-360500D02*
X580451Y-359333D01*
X581543Y-358458D01*
X583071Y-358167D01*
X584162Y-358458D01*
X585473Y-359333D01*
G01X534299Y-397333D02*
Y-414833D01*
X543033D01*
G01X556166D02*
Y-397333D01*
X553546Y-400833D01*
G01Y-414833D02*
X558786D01*
G01X672466D02*
X670719Y-414541D01*
X669191Y-413375D01*
X667881Y-411625D01*
X667007Y-409583D01*
X666571Y-407250D01*
Y-404916D01*
X667007Y-402583D01*
X667881Y-400541D01*
X669191Y-398792D01*
X670719Y-397625D01*
X672466Y-397333D01*
X674212Y-397625D01*
X675741Y-398792D01*
X677051Y-400541D01*
X677925Y-402583D01*
X678361Y-404916D01*
Y-407250D01*
X677925Y-409583D01*
X677051Y-411625D01*
X675741Y-413375D01*
X674212Y-414541D01*
X672466Y-414833D01*
G01X674212Y-410166D02*
X676833Y-414833D01*
G01X685163Y-397333D02*
Y-409875D01*
X686036Y-412500D01*
X687783Y-414250D01*
X689966Y-414833D01*
X692149Y-414250D01*
X693896Y-412500D01*
X694769Y-409875D01*
Y-397333D01*
G01X704846D02*
X710086D01*
G01X707466D02*
Y-414833D01*
G01X704846D02*
X710086D01*
G01X719944D02*
Y-397333D01*
X729988Y-414833D01*
Y-397333D01*
G01X747269Y-398792D02*
X745959Y-397916D01*
X744431Y-397333D01*
X742684D01*
X740719Y-398208D01*
X739191Y-399666D01*
X738099Y-401417D01*
X737226Y-404333D01*
X737007Y-406958D01*
X737444Y-409583D01*
X738099Y-411333D01*
X739409Y-413083D01*
X740938Y-414250D01*
X742466Y-414833D01*
X743994D01*
X745523Y-414250D01*
X746833Y-413375D01*
X747925Y-412209D01*
G01X759966Y-414833D02*
Y-406958D01*
X755599Y-397333D01*
G01X764333D02*
X759966Y-406958D01*
G01X650163Y-369833D02*
Y-352333D01*
X654529D01*
X656276Y-353208D01*
X657586Y-354375D01*
X658678Y-356124D01*
X659551Y-358167D01*
X659769Y-361083D01*
X659551Y-364000D01*
X658678Y-366042D01*
X657586Y-367792D01*
X656276Y-368958D01*
X654529Y-369833D01*
X650163D01*
G01X669191Y-361958D02*
X676178D01*
X675523Y-359916D01*
X674431Y-358750D01*
X672903Y-358167D01*
X671374Y-358458D01*
X670064Y-359333D01*
X669191Y-361375D01*
X668754Y-363125D01*
Y-364875D01*
X669191Y-366625D01*
X670283Y-368375D01*
X671593Y-369541D01*
X673121Y-369833D01*
X674649Y-369250D01*
X676178Y-367500D01*
G01X686691Y-367792D02*
X687783Y-368958D01*
X689311Y-369833D01*
X690621D01*
X691931Y-369250D01*
X692804Y-368375D01*
X693241Y-367209D01*
X693023Y-365458D01*
X692149Y-364583D01*
X688219Y-362833D01*
X687346Y-360791D01*
X687783Y-359333D01*
X688656Y-358458D01*
X689966Y-358167D01*
X691276Y-358458D01*
X692586Y-359333D01*
G01X707466Y-358167D02*
Y-369833D01*
G01Y-353500D02*
X707029Y-353208D01*
Y-352625D01*
X707466Y-352333D01*
X707903Y-352625D01*
Y-353208D01*
X707466Y-353500D01*
G01X721909Y-374208D02*
X723438Y-375375D01*
X725184Y-375666D01*
X726712Y-375375D01*
X728023Y-373917D01*
X728896Y-371875D01*
Y-358167D01*
G01Y-360500D02*
X728023Y-359333D01*
X726712Y-358458D01*
X725184Y-358167D01*
X723438Y-358750D01*
X722346Y-359916D01*
X721472Y-361958D01*
X721036Y-364000D01*
X721254Y-365750D01*
X722128Y-367792D01*
X723438Y-369250D01*
X725184Y-369833D01*
X726494Y-369541D01*
X728023Y-368375D01*
X728896Y-367209D01*
G01X738754Y-369833D02*
Y-358167D01*
G01Y-361083D02*
X739628Y-359625D01*
X740938Y-358458D01*
X742684Y-358167D01*
X744212Y-358458D01*
X745523Y-359625D01*
X746178Y-361666D01*
Y-369833D01*
G01X756691Y-361958D02*
X763678D01*
X763023Y-359916D01*
X761931Y-358750D01*
X760403Y-358167D01*
X758874Y-358458D01*
X757564Y-359333D01*
X756691Y-361375D01*
X756254Y-363125D01*
Y-364875D01*
X756691Y-366625D01*
X757783Y-368375D01*
X759093Y-369541D01*
X760621Y-369833D01*
X762149Y-369250D01*
X763678Y-367500D01*
G01X774409Y-369833D02*
Y-358167D01*
G01Y-360500D02*
X775501Y-359333D01*
X776593Y-358458D01*
X778121Y-358167D01*
X779212Y-358458D01*
X780523Y-359333D01*
G01X821166Y-397333D02*
X819419Y-397916D01*
X818109Y-399375D01*
X817236Y-401124D01*
X816581Y-403458D01*
X816363Y-406083D01*
X816581Y-408708D01*
X817236Y-411042D01*
X818109Y-412792D01*
X819419Y-414250D01*
X821166Y-414833D01*
X822912Y-414250D01*
X824223Y-412792D01*
X825096Y-411042D01*
X825751Y-408708D01*
X825969Y-406083D01*
X825751Y-403458D01*
X825096Y-401124D01*
X824223Y-399375D01*
X822912Y-397916D01*
X821166Y-397333D01*
G01X833863Y-411333D02*
X835172Y-413375D01*
X836919Y-414541D01*
X838884Y-414833D01*
X840631Y-414541D01*
X842378Y-413083D01*
X843469Y-411333D01*
X843688Y-409583D01*
X843251Y-407542D01*
X841723Y-406083D01*
X840194Y-405500D01*
X838229D01*
G01X840194D02*
X841504Y-404625D01*
X842596Y-403167D01*
X843033Y-401417D01*
X842596Y-399666D01*
X841504Y-398208D01*
X839539Y-397333D01*
X837574Y-397625D01*
X835609Y-398792D01*
G01X852236Y-415416D02*
X860096Y-397333D01*
G01X869518Y-400250D02*
X870828Y-398500D01*
X872356Y-397625D01*
X874103Y-397333D01*
X876286Y-397916D01*
X877814Y-399375D01*
X878251Y-401124D01*
X878033Y-402875D01*
X877159Y-404333D01*
X872793Y-407250D01*
X870828Y-409291D01*
X869518Y-412209D01*
X869081Y-414833D01*
X878251D01*
G01X887454Y-412792D02*
X888983Y-414250D01*
X890729Y-414833D01*
X892476Y-414250D01*
X894004Y-412500D01*
X895096Y-409875D01*
X895533Y-407250D01*
Y-404042D01*
X895096Y-401417D01*
X894004Y-399083D01*
X892694Y-397916D01*
X891166Y-397333D01*
X889419Y-397916D01*
X888109Y-399083D01*
X887236Y-400833D01*
X886799Y-403167D01*
X887236Y-405208D01*
X888328Y-407250D01*
X889638Y-408417D01*
X891166Y-408708D01*
X892912Y-408125D01*
X894223Y-406666D01*
X895533Y-404042D01*
G01X904736Y-415416D02*
X912596Y-397333D01*
G01X922018Y-400250D02*
X923328Y-398500D01*
X924856Y-397625D01*
X926603Y-397333D01*
X928786Y-397916D01*
X930314Y-399375D01*
X930751Y-401124D01*
X930533Y-402875D01*
X929659Y-404333D01*
X925293Y-407250D01*
X923328Y-409291D01*
X922018Y-412209D01*
X921581Y-414833D01*
X930751D01*
G01X943666Y-397333D02*
X941919Y-397916D01*
X940609Y-399375D01*
X939736Y-401124D01*
X939081Y-403458D01*
X938863Y-406083D01*
X939081Y-408708D01*
X939736Y-411042D01*
X940609Y-412792D01*
X941919Y-414250D01*
X943666Y-414833D01*
X945412Y-414250D01*
X946723Y-412792D01*
X947596Y-411042D01*
X948251Y-408708D01*
X948469Y-406083D01*
X948251Y-403458D01*
X947596Y-401124D01*
X946723Y-399375D01*
X945412Y-397916D01*
X943666Y-397333D01*
G01X961166Y-414833D02*
Y-397333D01*
X958546Y-400833D01*
G01Y-414833D02*
X963786D01*
G01X978229D02*
X978666Y-411042D01*
X979321Y-407833D01*
X980194Y-404916D01*
X981286Y-401708D01*
X983033Y-397333D01*
X974299D01*
G01X868863Y-369833D02*
Y-352333D01*
X873229D01*
X874976Y-353208D01*
X876286Y-354375D01*
X877378Y-356124D01*
X878251Y-358167D01*
X878469Y-361083D01*
X878251Y-364000D01*
X877378Y-366042D01*
X876286Y-367792D01*
X874976Y-368958D01*
X873229Y-369833D01*
X868863D01*
G01X895096D02*
Y-358167D01*
G01Y-360208D02*
X894223Y-359042D01*
X892912Y-358458D01*
X891384Y-358167D01*
X889856Y-358750D01*
X888546Y-359916D01*
X887672Y-361666D01*
X887236Y-364000D01*
X887672Y-366333D01*
X888546Y-368083D01*
X889856Y-369250D01*
X891384Y-369833D01*
X892912Y-369541D01*
X894223Y-368667D01*
X895096Y-367500D01*
G01X908666Y-352333D02*
Y-369833D01*
G01X905609Y-358167D02*
X911723D01*
G01X922891Y-361958D02*
X929878D01*
X929223Y-359916D01*
X928131Y-358750D01*
X926603Y-358167D01*
X925074Y-358458D01*
X923764Y-359333D01*
X922891Y-361375D01*
X922454Y-363125D01*
Y-364875D01*
X922891Y-366625D01*
X923983Y-368375D01*
X925293Y-369541D01*
X926821Y-369833D01*
X928349Y-369250D01*
X929878Y-367500D01*
G54D63*
X186454Y288824D03*
X191054D03*
X195654D03*
G54D54*
X7985Y225487D03*
G54D36*
X30742Y103542D03*
X53700Y118300D03*
X49018Y199384D03*
X106000Y51800D03*
X116500Y27400D03*
X214800Y115200D03*
G54D18*
X33500Y62600D03*
X48300Y59700D03*
X29700Y70800D03*
X70100Y60500D03*
X37331Y70804D03*
X38042Y109358D03*
X44800Y191610D03*
X30300Y284000D03*
X122300Y54000D03*
X97601Y32537D03*
X116600Y23500D03*
X184800Y70200D03*
X169487Y70136D03*
X198520Y113600D03*
X192771Y121500D03*
X215700Y185300D03*
G54D45*
X13200Y187900D03*
X183653Y191058D03*
G54D27*
G01X-351984Y-328833D02*
X-383984D01*
G01X-351984Y-344833D02*
Y-424833D01*
G01D02*
X998716D01*
G01X-355984Y-328833D02*
G02I-12000J0D01*
G01X-361134D02*
G02I-6850J0D01*
G01X-367984Y-344833D02*
Y-312833D01*
G01X-351984Y-344833D02*
X998716D01*
G01X-351984Y-380333D02*
X998716D01*
G01X63938Y11580D02*
X63819Y11461D01*
Y6299D01*
G01X52600Y23550D02*
Y23200D01*
X50100Y20700D01*
G01X36650Y58800D02*
X33500D01*
X33200Y59100D01*
G01X37281Y70804D02*
Y73779D01*
X37100Y73960D01*
G01X33150Y70800D02*
Y73850D01*
X33100Y73900D01*
G01X33481Y66704D02*
X33150Y67035D01*
Y70800D01*
G01X22150D02*
X20824Y69474D01*
X16813D01*
G01X12100Y73750D02*
Y71600D01*
X14226Y69474D01*
X16813D01*
G01X73000Y57200D02*
Y58729D01*
X73389Y59118D01*
Y60339D01*
X73550Y60500D01*
G01X76500Y54650D02*
X75550D01*
X73000Y57200D01*
G01X57400Y26400D02*
X54701D01*
X54051Y27050D01*
X52600D01*
G01X40150Y58800D02*
X43100D01*
X43900Y59600D01*
G01X40950Y48600D02*
Y50550D01*
X42300Y51900D01*
G01X16633Y128937D02*
X22383D01*
G01X39900Y84050D02*
Y84900D01*
X37500Y87300D01*
G01X57250Y118300D02*
Y119850D01*
X55700Y121400D01*
G01X41750Y118500D02*
Y115750D01*
X42500Y115000D01*
G01X53750Y118300D02*
X50400D01*
G01X28200Y121350D02*
X24450D01*
X24000Y120900D01*
G01X41492Y109358D02*
Y106258D01*
G01X23300Y105750D02*
X24950Y104100D01*
X27200D01*
G01D02*
X27758Y103542D01*
X30792D01*
G01X35750Y91400D02*
X32200D01*
G01X40000Y77100D02*
Y80450D01*
X39900Y80550D01*
G01X12100Y84750D02*
X7778D01*
X5662Y82634D01*
Y75866D01*
X7778Y73750D01*
X12100D01*
G01X22598Y154767D02*
Y150420D01*
G01X48250Y187610D02*
X51490D01*
X51500Y187600D01*
G01X48250Y195610D02*
X51390D01*
X51400Y195600D01*
G01X52568Y199384D02*
X56755D01*
G01X51076Y202657D02*
X49068Y200649D01*
Y199384D01*
G01X48250Y191610D02*
X51390D01*
X51500Y191500D01*
G01D02*
X53095D01*
X55129Y189466D01*
Y186011D01*
X54492Y185374D01*
G01X47412Y154167D02*
X44100D01*
G01X52400Y172050D02*
Y169300D01*
X51400Y168300D01*
G01X56400Y158800D02*
X53400Y161800D01*
X46000D01*
G01X39609Y159738D02*
X41471Y161600D01*
X45800D01*
X46000Y161800D01*
G01X50272Y285022D02*
X55200D01*
G01X28346Y246498D02*
Y250000D01*
G01D02*
Y253502D01*
G01X24844Y250000D02*
X28346D01*
G01D02*
X31848D01*
G01X32283Y299147D02*
Y303149D01*
G01D02*
Y307151D01*
G01X28281Y303149D02*
X32283D01*
G01D02*
X36285D01*
G01X32283Y318833D02*
Y322835D01*
G01D02*
Y326837D01*
G01X28281Y322835D02*
X32283D01*
G01D02*
X36285D01*
G01X109550Y51800D02*
X112900D01*
G01X100900Y44150D02*
X97200D01*
G01X132600Y50550D02*
Y53800D01*
G01X78838Y11602D02*
X78819Y11583D01*
Y6299D01*
G01X120050Y27400D02*
Y29150D01*
X119200Y30000D01*
Y30900D01*
G01X104300Y24950D02*
Y22200D01*
X104900Y21600D01*
Y21400D01*
G01X132600Y37650D02*
X132500Y37750D01*
Y41200D01*
G01X79200Y62550D02*
X76650D01*
X75300Y63900D01*
X75100D01*
G01X79150Y47000D02*
Y43750D01*
X79000Y43600D01*
G01X100900Y40650D02*
X100650D01*
X99839Y39839D01*
X99818D01*
X97713Y37734D01*
Y37713D01*
X97500Y37500D01*
Y36600D01*
G01X97551Y32537D02*
X97400Y32386D01*
Y29300D01*
G01X133450Y24000D02*
Y28750D01*
X132600Y29600D01*
G01D02*
Y34150D01*
G01X120050Y23500D02*
X120950Y22600D01*
X124300D01*
G01X75604Y83819D02*
Y86996D01*
X75600Y87000D01*
G01X79200Y73550D02*
Y76050D01*
X79750Y76600D01*
G01X211216Y-344833D02*
Y-424833D01*
G01X222500Y35100D02*
Y38750D01*
G01X197760Y53277D02*
X194560D01*
G01X220732Y49139D02*
Y46039D01*
G01X168858Y12000D02*
X168839Y11981D01*
Y6299D01*
G01X183500Y43250D02*
Y45800D01*
X182800Y46500D01*
G01X176300Y43950D02*
X173800D01*
X172800Y44950D01*
G01X174350Y48800D02*
Y51950D01*
X174300Y52000D01*
G01X192500Y70250D02*
Y73385D01*
G01X218300Y35750D02*
Y32700D01*
G01X219500Y53150D02*
X222609D01*
G01X179093Y38185D02*
X176828Y40450D01*
X176300D01*
G01X164850Y48200D02*
Y45650D01*
X163000Y43800D01*
G01X183500Y39750D02*
X182478D01*
X180000Y42228D01*
Y42250D01*
X179500Y42750D01*
G01X177250Y70200D02*
Y66750D01*
X178843Y65157D01*
Y62700D01*
G01X172937Y70136D02*
X177186D01*
X177250Y70200D01*
G01X178843Y62700D02*
Y59000D01*
G01X188250Y66000D02*
Y70200D01*
G01Y62546D02*
Y66000D01*
G01X209522Y48762D02*
Y47755D01*
X207293Y45526D01*
G01X215378Y25855D02*
X214557D01*
X213700Y24998D01*
X212098D01*
X211900Y24800D01*
G01X197760Y56777D02*
X194560D01*
G01X215520Y140500D02*
X211000D01*
G01X202783Y128937D02*
X208170D01*
G01X219000Y104060D02*
X215800D01*
G01X218350Y111900D02*
Y115200D01*
G01X184700Y112500D02*
X184800Y112600D01*
Y114600D01*
X185900Y115700D01*
G01X192500Y73385D02*
X192724Y73609D01*
Y77280D01*
G01X168966Y86980D02*
X174600D01*
G01X218350Y115200D02*
Y119000D01*
G01X215516Y132335D02*
X218700D01*
G01X215800Y107560D02*
X219000D01*
G01X201970Y113600D02*
X203570Y112000D01*
X214500D01*
G01D02*
X214850Y112350D01*
Y115200D01*
G01X168936Y79463D02*
Y83450D01*
X168966Y83480D01*
G01X188750Y90000D02*
Y88175D01*
X192691Y84234D01*
G01D02*
X192724Y84201D01*
Y80780D01*
G01X214800Y128309D02*
X213700Y127209D01*
Y127001D01*
X212720Y126021D01*
Y125765D01*
X211842Y124887D01*
X211587D01*
X211500Y124800D01*
X204801D01*
X204497Y124496D01*
X204496D01*
X203738Y123738D01*
X198459D01*
X196221Y121500D01*
G01X218832Y128309D02*
X214800D01*
G01X219150Y181300D02*
Y178000D01*
G01X205848Y199637D02*
X208687D01*
X210950Y201900D01*
G01X214350Y206700D02*
Y208038D01*
X216350Y210038D01*
X223454D01*
X224000Y210584D01*
G01X219150Y185300D02*
X223200D01*
G01X214450Y201900D02*
Y206600D01*
X214350Y206700D01*
G01X223200Y185300D02*
Y182400D01*
X222800Y182000D01*
G01X220723Y287895D02*
X220678Y287850D01*
Y284412D01*
G01X188583Y246498D02*
Y250000D01*
G01D02*
Y253502D01*
G01X185081Y250000D02*
X188583D01*
G01D02*
X192085D01*
G01X192520Y299147D02*
Y303149D01*
G01D02*
Y307151D01*
G01X188518Y303149D02*
X192520D01*
G01D02*
X196522D01*
G01X192520Y318833D02*
Y322835D01*
G01D02*
Y326837D01*
G01X188518Y322835D02*
X192520D01*
G01D02*
X196522D01*
G01X348716Y-344833D02*
Y-424833D01*
G01X463716Y-344833D02*
Y-424833D01*
G01X631216Y-344833D02*
Y-424833D01*
G01X801216Y-344833D02*
Y-424833D01*
G01X998716Y-344833D02*
Y-424833D01*
G01X1026716Y-328833D02*
G02I-12000J0D01*
G01X1021566D02*
G02I-6850J0D01*
G01X1014716Y-344833D02*
Y-312833D01*
G01X1030716Y-328833D02*
X998716D01*
X48000Y38000D03*
X58700Y55600D03*
X33200Y59100D03*
X35744Y51944D03*
X41000Y36900D03*
X50100Y20700D03*
X57450Y35400D03*
X55500Y42000D03*
X69446Y48262D03*
X70360Y25750D03*
X73000Y57200D03*
X57400Y26400D03*
X63300Y37300D03*
X43900Y59600D03*
X42300Y51900D03*
X50100Y34500D03*
X68838Y12300D03*
X39400Y41000D03*
X36900Y17600D03*
X26000Y51600D03*
X19763Y92200D03*
X55700Y121400D03*
X22800Y112600D03*
X32100Y114900D03*
X42500Y115000D03*
X47300Y107940D03*
X34900Y106742D03*
X37100Y73960D03*
X37500Y87300D03*
X17700Y89400D03*
X50400Y118300D03*
X24000Y120900D03*
X41492Y106258D03*
X27200Y104100D03*
X33100Y73900D03*
X32200Y91400D03*
X40000Y77100D03*
X23093Y99967D03*
X9000Y81250D03*
Y77250D03*
X40900Y88400D03*
X46200Y111200D03*
X15857Y202417D03*
X47300Y168700D03*
X15007Y163581D03*
X51400Y168300D03*
X16253Y180320D03*
X20539Y163381D03*
X9581Y160069D03*
X11840Y177692D03*
X4100Y294900D03*
X60300Y290000D03*
X17100Y278300D03*
X13650Y278350D03*
X26270Y282547D03*
X22820Y282597D03*
X18600Y338800D03*
X4200Y312100D03*
Y329000D03*
X42800Y338500D03*
X29000Y338600D03*
X60400Y305900D03*
X60500Y316400D03*
X60300Y331800D03*
X60400Y350300D03*
X44000Y350200D03*
X20100Y350300D03*
X4400D03*
X99300Y25700D03*
X136439Y31761D03*
X132500Y41200D03*
X79000Y43600D03*
X75100Y63900D03*
X118100Y45000D03*
X104900Y21400D03*
X114900Y39900D03*
X97200Y44150D03*
X132600Y53800D03*
X119200Y30900D03*
X97500Y36600D03*
X97400Y29300D03*
X132600Y29600D03*
X124300Y22600D03*
X76900Y15500D03*
X73838Y12100D03*
X126742Y15658D03*
X82200Y60800D03*
X100100Y56300D03*
X125700Y26500D03*
X75600Y87000D03*
Y91500D03*
X79750Y76600D03*
X79604Y86869D03*
X219300Y-13900D03*
X208500Y-22000D03*
X204340Y71660D03*
X186200Y14900D03*
X222500Y35100D03*
X208500Y9400D03*
X203300Y14800D03*
X217800Y14300D03*
X169750Y62500D03*
X163452Y32350D03*
X161300Y51500D03*
X174300Y52000D03*
X172800Y44950D03*
X182800Y46500D03*
X220732Y46039D03*
X194560Y53277D03*
X218300Y32700D03*
X222609Y53150D03*
X179093Y38185D03*
X163000Y43800D03*
X179500Y42750D03*
X178843Y59000D03*
X188250Y66000D03*
X207293Y45526D03*
X211900Y24800D03*
X194560Y56777D03*
X160800Y72000D03*
X154444Y72036D03*
X208900Y59000D03*
X160794Y86162D03*
X219000Y104060D03*
X211000Y140500D03*
X174600Y86980D03*
X198100Y104000D03*
X184700Y112500D03*
X218350Y111900D03*
X204818Y118400D03*
X210276Y122000D03*
X192500Y73385D03*
X218700Y132335D03*
X219000Y107560D03*
X214500Y112000D03*
X192691Y84234D03*
X214800Y128309D03*
X193500Y135835D03*
X190900Y112200D03*
X159711Y82091D03*
X156891Y79378D03*
X184900Y106300D03*
X171263Y92837D03*
X214119Y216661D03*
X224000Y210584D03*
X207750Y224016D03*
X220200Y151000D03*
X219269Y216635D03*
X214401Y281884D03*
X215411Y270499D03*
X209506Y229990D03*
X215916Y232222D03*
X222500Y344500D03*
X200200Y343900D03*
X188300Y343400D03*
X193300Y337900D03*
X211900Y337500D03*
X219900Y330500D03*
X214200Y325100D03*
X209500Y350300D03*
X188000D03*
X172300Y337600D03*
Y350200D03*
X220550Y306050D03*
X224000Y306000D03*
X228400Y-21400D03*
X228600Y42000D03*
X228300Y6100D03*
X228400Y22800D03*
X228600Y69200D03*
Y85900D03*
X227800Y322200D03*
X228500Y337100D03*
X228400Y350200D03*
G54D73*
G01X48000Y38000D02*
X47060Y37060D01*
Y32450D01*
G01D02*
X48310Y31200D01*
X51400D01*
X52500Y32300D01*
X53250D01*
G01D02*
X55162Y30388D01*
X55434D01*
X56084Y29738D01*
X59862D01*
X62440Y27160D01*
Y25750D01*
G01X47300Y75660D02*
X54240D01*
X61000Y68900D01*
Y60500D01*
G01X58700Y55600D02*
X61000Y57900D01*
Y60500D01*
G01X58819Y6299D02*
Y12489D01*
X62249Y15919D01*
X73310D01*
X77173Y19782D01*
Y23627D01*
G01X64450Y51470D02*
X67597D01*
X67629Y51438D01*
X69131D01*
X71800Y48769D01*
Y43482D01*
X77173Y38109D01*
Y23627D01*
G01X53819Y6299D02*
Y11980D01*
X59074Y17235D01*
Y17236D01*
X60932Y19094D01*
X71794D01*
X73998Y21298D01*
Y28000D01*
X73400Y28598D01*
Y32000D01*
G01X64450Y47530D02*
X67294D01*
X68400Y46424D01*
Y42391D01*
X73400Y37391D01*
Y32000D01*
G01X48150Y51470D02*
X50965D01*
X52625Y49810D01*
Y44754D01*
X51962Y44091D01*
Y43962D01*
X51800Y43800D01*
Y38000D01*
G01X50100Y34500D02*
X51800Y36200D01*
Y38000D01*
G01X39400Y41000D02*
Y42500D01*
X41300Y44400D01*
G01X48150Y47530D02*
X45308D01*
X42539Y44761D01*
X41661D01*
X41300Y44400D01*
G01X68838Y12300D02*
X68819Y12281D01*
Y6299D01*
G01X51750Y59700D02*
X55200D01*
X56000Y60500D01*
G01X47300Y70540D02*
X52060D01*
X56500Y66100D01*
Y61000D01*
X56000Y60500D01*
G01X36950Y62600D02*
X41300D01*
G01X47300Y67980D02*
X44580D01*
X43462Y66862D01*
Y64762D01*
X41300Y62600D01*
G01X65000Y25750D02*
Y23000D01*
X64269Y22269D01*
X57769D01*
X51849Y16349D01*
X49900D01*
G01X36900Y17600D02*
X38151Y16349D01*
X49900D01*
G01X41940Y25950D02*
X39350D01*
X36300Y29000D01*
Y40300D01*
X32400Y44200D01*
Y47300D01*
X31600Y48100D01*
G01X26000Y51600D02*
X28100D01*
X31600Y48100D01*
G01X48250Y59700D02*
Y58450D01*
X45262Y55462D01*
X31938D01*
X29400Y58000D01*
Y58900D01*
G01X34400Y79220D02*
X30236D01*
X25650Y74634D01*
Y70800D01*
G01D02*
Y62650D01*
X29400Y58900D01*
G01X33450Y62600D02*
X31700D01*
X29650Y64650D01*
Y66500D01*
G01X34400Y76660D02*
X31460D01*
X29650Y74850D01*
Y70800D01*
G01D02*
Y66500D01*
G01X67560Y32250D02*
Y38480D01*
X67300Y38740D01*
G01X48150Y53435D02*
X54565D01*
X55800Y52200D01*
Y46904D01*
X60314Y42390D01*
X63910D01*
X67300Y39000D01*
Y38740D01*
G01X44500Y32450D02*
Y38816D01*
X44416Y38900D01*
Y38922D01*
G01X48150Y45565D02*
Y44050D01*
X44416Y40316D01*
Y38922D01*
G01X69500Y65420D02*
X66520D01*
X65500Y64400D01*
Y60900D01*
X66200Y60200D01*
G01X70050Y60500D02*
X69550Y60000D01*
X66400D01*
X66200Y60200D01*
G01X36981Y66704D02*
X40231D01*
X40631Y67104D01*
G01X47300Y73100D02*
X43077D01*
X40781Y70804D01*
G01D02*
Y67254D01*
X40631Y67104D01*
G01X69500Y67980D02*
X73200D01*
X73520Y68300D01*
X75100D01*
G01X69500Y70540D02*
X72040D01*
X75604Y74104D01*
Y76400D01*
G01X64450Y53435D02*
X61035D01*
X59500Y51900D01*
Y47695D01*
X61630Y45565D01*
X64450D01*
G01X71500Y53200D02*
X71265Y53435D01*
X64450D01*
G01X75650Y47000D02*
X73800Y48850D01*
Y50900D01*
X71500Y53200D01*
G01X34400Y84340D02*
X30160D01*
X29400Y85100D01*
Y88200D01*
X28000Y89600D01*
X24900D01*
G01X19763Y92200D02*
X20382Y91581D01*
Y91518D01*
X22300Y89600D01*
X24900D01*
G01X102638Y6299D02*
Y18546D01*
X94062Y27122D01*
Y51450D01*
X95800Y53188D01*
Y66377D01*
X93764Y68413D01*
Y93261D01*
X93762Y93263D01*
Y95627D01*
X60162Y129227D01*
Y130537D01*
X60188Y130563D01*
Y162912D01*
X57962Y165138D01*
X55300D01*
G01X17323Y159819D02*
X14935D01*
X9088Y153972D01*
Y103403D01*
X11753Y100738D01*
X22322D01*
X23093Y99967D01*
G01X12900Y107500D02*
X14150Y106250D01*
X17700D01*
G01D02*
X18050D01*
X21050Y109250D01*
X23300D01*
G01X12900Y107500D02*
X12014Y108386D01*
Y153114D01*
X13667Y154767D01*
X16598D01*
G01X16633Y146653D02*
X47933D01*
G01X50912Y154167D02*
Y152712D01*
X47933Y149733D01*
Y146653D01*
G01X16598Y154767D02*
Y146688D01*
X16633Y146653D01*
G01X23300Y109250D02*
X24850D01*
X25818Y108282D01*
X29058D01*
G01X21600Y79220D02*
X19420D01*
X18600Y78400D01*
X15800D01*
G01D02*
X14950D01*
X12100Y81250D01*
G01D02*
X9000D01*
G01X21600Y76660D02*
Y75071D01*
X20155Y73626D01*
X16174D01*
G01D02*
X15724D01*
X12100Y77250D01*
G01D02*
X9000D01*
G01X7200Y199250D02*
X4400Y196450D01*
Y184600D01*
X3738Y183938D01*
Y101185D01*
X9761Y95162D01*
X27042D01*
G01D02*
X33553D01*
X37195Y98804D01*
X73085D01*
X83064Y88825D01*
Y72849D01*
X83063Y72848D01*
Y63720D01*
X84750Y62033D01*
Y57855D01*
X83362Y56467D01*
Y55886D01*
X83361Y55885D01*
Y51451D01*
X83362Y51450D01*
Y16614D01*
X86890Y13086D01*
Y6299D01*
G01X9050Y191750D02*
X8839Y191539D01*
Y183945D01*
X6413Y181519D01*
Y102294D01*
X10788Y97919D01*
X32526D01*
X37527Y102920D01*
X45314D01*
G01X90040Y6299D02*
Y13720D01*
X86037Y17723D01*
Y52559D01*
X86036Y52560D01*
Y54776D01*
X87500Y56240D01*
Y63325D01*
X85738Y65087D01*
Y71739D01*
X85739Y71740D01*
Y89934D01*
X73673Y102000D01*
X57000D01*
X56075Y102925D01*
X45319D01*
X45314Y102920D01*
G01X67282Y114234D02*
X63263Y118253D01*
Y122342D01*
X57487Y128118D01*
Y131646D01*
X57513Y131672D01*
Y152966D01*
X52974Y157505D01*
X42716D01*
X39711Y154500D01*
X30644D01*
X25565Y159579D01*
Y168782D01*
X23704Y170643D01*
Y176761D01*
X32190Y185247D01*
Y197801D01*
X34488Y200099D01*
X37902D01*
X39869Y202066D01*
X45744D01*
X58736Y215058D01*
Y271964D01*
X39375Y291325D01*
X25159D01*
X12598Y303886D01*
Y312992D01*
G01X99489Y6299D02*
Y17911D01*
X91387Y26013D01*
Y52559D01*
X93100Y54272D01*
Y65293D01*
X91088Y67305D01*
Y69521D01*
X91089Y69522D01*
Y92152D01*
X71041Y112200D01*
X69316D01*
X67282Y114234D01*
G01X93189Y6299D02*
Y10619D01*
X92800Y11008D01*
Y14744D01*
X88712Y18832D01*
Y53668D01*
X90300Y55256D01*
Y64309D01*
X88413Y66196D01*
Y70630D01*
X88414Y70631D01*
Y91043D01*
X73857Y105600D01*
X69150D01*
G01X33700Y121550D02*
X35650Y123500D01*
X53079D01*
X54318Y124739D01*
X57082D01*
X60588Y121233D01*
Y116412D01*
X61900Y115100D01*
Y109900D01*
X59940Y107940D01*
X58250D01*
G01D02*
Y106550D01*
X59200Y105600D01*
X69150D01*
G01X31500Y110252D02*
X34148D01*
X34570Y109830D01*
X36180D01*
X36652Y109358D01*
X37992D01*
G01X38250Y118500D02*
X36900Y117150D01*
Y113400D01*
X37000Y113300D01*
G01X37992Y109358D02*
Y112308D01*
X37000Y113300D01*
G01X47300Y93580D02*
X44720D01*
X42900Y95400D01*
X41500D01*
X41200Y95100D01*
G01D02*
X39250Y93150D01*
Y91400D01*
G01X46200Y111200D02*
X46900Y110500D01*
X51750D01*
G01X39250Y91400D02*
X40900Y89750D01*
Y88400D01*
G01X51750Y113060D02*
X49040D01*
X45900Y116200D01*
Y118700D01*
G01D02*
Y118948D01*
X44023Y120825D01*
X36791D01*
X34016Y118050D01*
X33700D01*
G01X28200Y117850D02*
Y115200D01*
X29058Y114342D01*
Y112222D01*
G01X33700Y118050D02*
X28400D01*
X28200Y117850D01*
G01X15857Y202417D02*
X14002Y204272D01*
Y213349D01*
X32374Y231721D01*
Y234342D01*
X34252Y236220D01*
X38189D01*
G01X28346Y240157D02*
X22960Y234771D01*
Y229875D01*
X10520Y217435D01*
X10519D01*
G01X28346Y232283D02*
Y231477D01*
X8392Y211523D01*
Y207860D01*
G01X37283Y173228D02*
X45373Y165138D01*
X55300D01*
G01X15300Y288650D02*
X38266D01*
X56061Y270855D01*
Y216167D01*
X44635Y204741D01*
X38760D01*
X36793Y202774D01*
X33379D01*
X29515Y198910D01*
Y186356D01*
X21029Y177870D01*
Y169116D01*
X22890Y167255D01*
Y162056D01*
X20653Y159819D01*
X17323D01*
G01X33609Y159738D02*
X29371D01*
X29232Y159877D01*
G01D02*
X28240Y160869D01*
Y172271D01*
X27283Y173228D01*
G01X16253Y180320D02*
X16538Y180035D01*
Y173177D01*
G01Y167477D02*
Y166158D01*
X19315Y163381D01*
X20539D01*
G01X44750Y191610D02*
Y195610D01*
G01D02*
X42090D01*
X40760Y194280D01*
X37190D01*
G01Y191720D02*
X41140D01*
X44750Y188110D01*
Y187610D01*
G01X49322Y183538D02*
X50273Y182587D01*
X50278D01*
X50991Y181874D01*
X54492D01*
G01X44750Y187610D02*
Y185321D01*
X46533Y183538D01*
X49322D01*
G01X47699Y179634D02*
X46604Y180729D01*
X44471D01*
X41420Y183780D01*
Y187162D01*
X39422Y189160D01*
X37190D01*
G01X48300Y175550D02*
X52400D01*
G01X48300D02*
Y179033D01*
X47699Y179634D01*
G01X21010Y191720D02*
X17020D01*
X13200Y187900D01*
G01X21010Y194280D02*
X24966D01*
X25645Y194959D01*
Y198359D01*
X24593Y199411D01*
X13989D01*
X12200Y201200D01*
G01X7200Y202750D02*
X10650D01*
X12200Y201200D01*
G01X9050Y195250D02*
X13646D01*
G01D02*
X16750D01*
X18340Y196840D01*
X21010D01*
G01X9581Y160069D02*
X10579D01*
X12600Y162090D01*
Y167477D01*
G01Y173177D02*
Y176932D01*
X11840Y177692D01*
G01X15300Y288650D02*
Y297400D01*
X9238Y303462D01*
Y320738D01*
X19400Y330900D01*
X34900D01*
X42126Y323674D01*
Y322835D01*
G01X50272Y288522D02*
X54422D01*
X55800Y289900D01*
Y292900D01*
G01X51968Y312992D02*
X55800Y309160D01*
Y292900D01*
G01X99300Y25700D02*
X99400D01*
X102150Y28450D01*
X104300D01*
G01D02*
Y30288D01*
X106048Y32036D01*
Y35685D01*
G01X136439Y31761D02*
Y46461D01*
X136400Y46500D01*
G01X127770Y43591D02*
Y45870D01*
X128950Y47050D01*
X132600D01*
G01D02*
X135850D01*
X136400Y46500D01*
G01X118839Y6299D02*
Y11864D01*
X120938Y13963D01*
Y14516D01*
X127084Y20662D01*
X134834D01*
X139114Y24942D01*
Y89314D01*
X158600Y108800D01*
X163734D01*
X165206Y110272D01*
G01X76900Y15500D02*
X80000D01*
X83819Y11681D01*
Y6299D01*
G01X73838Y12100D02*
X73819Y12081D01*
Y6299D01*
G01X126742Y15658D02*
X123839Y12755D01*
Y6299D01*
G01X133839D02*
Y11739D01*
X137100Y15000D01*
Y15300D01*
X142700Y20900D01*
Y86300D01*
X161400Y105000D01*
X171900D01*
G01X205500Y172650D02*
Y170129D01*
X223600Y152029D01*
Y103900D01*
X219600Y99900D01*
X211900D01*
X209605Y97605D01*
X196697D01*
X193351Y100951D01*
X188917D01*
X188916Y100950D01*
X182682D01*
X182007Y101625D01*
X163289D01*
X145883Y84219D01*
Y54000D01*
G01X143839Y6299D02*
Y17939D01*
X145883Y19983D01*
Y54000D01*
G01X79200Y66050D02*
X77871D01*
X75621Y68300D01*
X75100D01*
G01X79200Y70050D02*
Y66050D01*
G01X108150Y24900D02*
Y28550D01*
X108300Y28700D01*
G01X108018Y35685D02*
Y31100D01*
X108300Y30818D01*
Y28700D01*
G01X109988Y35685D02*
Y32812D01*
X112600Y30200D01*
Y28700D01*
G01X111650Y24900D02*
X112600Y25850D01*
Y28700D01*
G01X125800Y43591D02*
Y50000D01*
X126100Y50300D01*
G01D02*
Y53650D01*
X125750Y54000D01*
G01X123830Y43591D02*
Y46770D01*
X121700Y48900D01*
Y50300D01*
G01X122250Y54000D02*
Y50850D01*
X121700Y50300D01*
G01X98071Y51675D02*
X98196Y51800D01*
X101800D01*
G01X109988Y44885D02*
Y48112D01*
X108800Y49300D01*
X107500D01*
X106300Y50500D01*
Y51550D01*
X106050Y51800D01*
G01D02*
X101800D01*
G01X123830Y34391D02*
Y37585D01*
X122815Y38600D01*
X118800D01*
X116850Y36650D01*
Y34100D01*
G01X116550Y27400D02*
Y33800D01*
X116850Y34100D01*
G01X116550Y23500D02*
Y27400D01*
G01X101051Y32537D02*
Y36351D01*
X101200Y36500D01*
G01X108018Y44885D02*
Y41118D01*
X106500Y39600D01*
X104572D01*
X102284Y37312D01*
X102033D01*
X101222Y36501D01*
X101201D01*
X101200Y36500D01*
G01X125800Y34391D02*
Y31200D01*
X129200Y27800D01*
G01X129950Y24000D02*
Y27050D01*
X129200Y27800D01*
G01X82200Y60800D02*
X80900D01*
X78600Y58500D01*
G01X80600Y54650D02*
X78600Y56650D01*
Y58500D01*
G01X100100Y56300D02*
X101100Y55300D01*
X113300D01*
X115300Y53300D01*
Y50700D01*
X111958Y47358D01*
Y44885D01*
G01X80600Y51150D02*
X76500D01*
G01D02*
Y49072D01*
X75812Y48384D01*
Y47162D01*
X75650Y47000D01*
G01X125700Y26500D02*
Y27500D01*
X121860Y31340D01*
Y34391D01*
G01X75604Y80319D02*
Y76400D01*
G01X79604Y80319D02*
X75604D01*
G01X170750Y54440D02*
X170850Y54340D01*
Y48800D01*
G01D02*
X170700Y48650D01*
Y46400D01*
X164942Y40642D01*
X163452D01*
G01X160794Y86162D02*
X160608D01*
X159983Y85537D01*
X158553D01*
X154011Y80995D01*
Y78048D01*
X157599Y74460D01*
Y65020D01*
X157686Y64933D01*
Y42014D01*
X159058Y40642D01*
X163452D01*
G01X204340Y71660D02*
X198400D01*
G01X153839Y6299D02*
Y12661D01*
X151336Y15164D01*
Y31673D01*
X151249Y31760D01*
Y41341D01*
X151336Y41428D01*
Y62300D01*
G01D02*
Y62301D01*
X151249Y62388D01*
Y76840D01*
X151336Y76927D01*
Y82104D01*
X165507Y96275D01*
X179789D01*
X180464Y95600D01*
X191134D01*
X194479Y92255D01*
X213155D01*
X215400Y94500D01*
X222500D01*
X228950Y100950D01*
Y312381D01*
X225100Y316231D01*
X222189D01*
G01X207150Y40470D02*
X210406D01*
X211443Y41507D01*
X213131D01*
X214462Y40176D01*
Y32601D01*
X210697Y28836D01*
X207700D01*
X206664Y27800D01*
X203391D01*
X195600Y20009D01*
X193710D01*
G01X178839Y6299D02*
Y14339D01*
X184509Y20009D01*
X193710D01*
G01X173839Y6299D02*
Y14936D01*
X181167Y22264D01*
G01X207150Y36530D02*
X210470D01*
X211287Y35713D01*
Y33917D01*
X209381Y32011D01*
X206190D01*
X205569Y31390D01*
X202129D01*
X194939Y24200D01*
X183103D01*
X181167Y22264D01*
G01X163839Y6299D02*
Y12409D01*
X167269Y15839D01*
X169339D01*
X172392Y18892D01*
G01X190850Y40470D02*
X196306D01*
X198885Y37891D01*
Y32637D01*
X193748Y27500D01*
X181000D01*
X172392Y18892D01*
G01X190850Y36530D02*
X194070D01*
X195200Y35400D01*
Y33443D01*
X192557Y30800D01*
X178897D01*
X172328Y24231D01*
G01X158839Y6299D02*
Y11900D01*
X165953Y19014D01*
X167111D01*
X172328Y24231D01*
G01X205500Y52250D02*
Y55700D01*
X205700Y55900D01*
G01X198400Y66540D02*
X203560D01*
X206100Y64000D01*
Y56300D01*
X205700Y55900D01*
G01X174600Y75660D02*
Y74600D01*
X173474Y73474D01*
X171553D01*
X169437Y71358D01*
Y70136D01*
G01D02*
X167904D01*
X162610Y75430D01*
G01X201500Y52250D02*
Y57000D01*
X201600Y57100D01*
G01X198400Y63980D02*
X201120D01*
X202364Y62736D01*
Y57864D01*
X201600Y57100D01*
G01X170750Y57000D02*
X162317D01*
X160861Y58456D01*
Y63661D01*
X161075Y63875D01*
Y63967D01*
X161500Y64392D01*
Y65600D01*
G01X160800Y72000D02*
Y69600D01*
X161500Y68900D01*
Y65600D01*
G01X169952Y35522D02*
Y32500D01*
X167352Y29900D01*
X157600D01*
X154424Y33076D01*
Y40024D01*
G01D02*
Y40025D01*
X154511Y40112D01*
Y63617D01*
X154424Y63704D01*
Y72016D01*
X154444Y72036D01*
G01X148839Y6299D02*
Y12861D01*
X148558Y13142D01*
Y43046D01*
G01X209900Y172650D02*
Y169513D01*
X226275Y153138D01*
Y102775D01*
X220700Y97200D01*
X213900D01*
X211630Y94930D01*
X195588D01*
X192242Y98276D01*
X190026D01*
X190025Y98275D01*
X181573D01*
X180898Y98950D01*
X164398D01*
X148661Y83213D01*
Y78036D01*
X148574Y77949D01*
Y61279D01*
X148661Y61192D01*
Y52994D01*
X148558Y52891D01*
Y43046D01*
G01X187400Y78220D02*
X184720D01*
X180750Y74250D01*
Y70200D01*
G01X205500Y48750D02*
X202150Y45400D01*
X193900D01*
X185786Y53514D01*
X184486D01*
X183300Y54700D01*
G01X180750Y70200D02*
Y67971D01*
X182237Y66484D01*
Y55763D01*
X183300Y54700D01*
G01X197500Y48750D02*
X201500D01*
G01X197500D02*
X194450D01*
X184912Y58288D01*
Y67938D01*
X184750Y68100D01*
Y70200D01*
G01D02*
X187400Y72850D01*
Y75660D01*
G01X164250Y59560D02*
Y62650D01*
X166800Y65200D01*
X173195D01*
X174700Y63695D01*
Y58100D01*
X178700Y54100D01*
Y52500D01*
G01X190850Y42435D02*
Y43950D01*
X184461Y50339D01*
X180861D01*
X178700Y52500D01*
G01X163452Y38082D02*
X172018D01*
X175535Y34565D01*
X177637D01*
G01D02*
X190850D01*
G01X219500Y56650D02*
Y58500D01*
X220600Y59600D01*
Y61420D01*
G01X188250Y59046D02*
X190846D01*
X192366Y60566D01*
Y61922D01*
G01X198400Y69100D02*
X195926D01*
X193576Y66750D01*
X192500D01*
G01D02*
X192366Y66616D01*
Y61922D01*
G01X217732Y42900D02*
X217832Y43000D01*
X220000D01*
X220750Y42250D01*
X222500D01*
G01X218300Y39250D02*
X217732Y39818D01*
Y42900D01*
G01X222500Y42250D02*
X223787Y43537D01*
Y44372D01*
X224547Y45132D01*
Y62358D01*
X222925Y63980D01*
X220600D01*
G01Y66540D02*
X224760D01*
X227300Y64000D01*
Y44000D01*
X226462Y43162D01*
Y34030D01*
X226448Y34016D01*
Y33705D01*
X223378Y30635D01*
G01X215378Y29355D02*
X219378D01*
G01D02*
X222098D01*
X223378Y30635D01*
G01X208900Y59000D02*
Y58200D01*
X211000Y56100D01*
X211300D01*
G01X215300Y56650D02*
X214750Y56100D01*
X211300D01*
G01X207150Y42435D02*
X209735D01*
X212290Y44990D01*
X214033D01*
G01X207150Y34565D02*
X203299D01*
X202300Y35564D01*
Y40909D01*
X203691Y42300D01*
X207015D01*
X207150Y42435D01*
G01X217232Y49139D02*
Y47832D01*
X214390Y44990D01*
X214033D01*
G01X209522Y52262D02*
X213162D01*
X214050Y53150D01*
X215300D01*
G01D02*
X215950D01*
X217232Y51868D01*
Y49139D01*
G01X180600Y88400D02*
X179575Y89425D01*
X177843D01*
X176877Y90391D01*
X164837D01*
X160794Y86348D01*
Y86162D01*
G01X187400Y83340D02*
X183238D01*
X180600Y85978D01*
Y88400D01*
G01X193583Y173228D02*
X188711Y178100D01*
X179700D01*
X172400Y170800D01*
Y134100D01*
X169000Y130700D01*
Y114066D01*
X165206Y110272D01*
G01X207534Y115430D02*
X204861D01*
X203352Y116939D01*
X200165D01*
X198470Y115244D01*
Y113600D01*
G01X193500Y135835D02*
X215516D01*
G01X208170Y146653D02*
X212717Y151200D01*
X215600D01*
G01X176870Y146653D02*
X208170D01*
G01X190900Y112200D02*
Y114700D01*
X191900Y115700D01*
G01X215520Y146500D02*
X215600Y146580D01*
Y151200D01*
G01X215516Y135835D02*
X215835D01*
X218100Y138100D01*
Y143920D01*
X215520Y146500D01*
G01X198470Y113600D02*
X196800D01*
X194700Y115700D01*
X191900D01*
G01X174600Y78220D02*
X172275D01*
X171055Y77000D01*
X169973D01*
X168936Y75963D01*
G01D02*
X165861D01*
X164700Y77124D01*
Y82300D01*
G01X159711Y82091D02*
X164491D01*
X164700Y82300D01*
G01X156891Y79378D02*
X159117Y77152D01*
X160888D01*
X162610Y75430D01*
G01X209550Y102940D02*
Y102040D01*
X207790Y100280D01*
X197806D01*
X194460Y103626D01*
X187808D01*
X187807Y103625D01*
X183791D01*
X182566Y104850D01*
X180800D01*
G01D02*
X172050D01*
X171900Y105000D01*
G01X218832Y124809D02*
X216909D01*
X215000Y122900D01*
G01X209976Y117400D02*
X212500D01*
X214100Y119000D01*
X214850D01*
G01D02*
Y122750D01*
X215000Y122900D01*
G01X198400Y89580D02*
X192670D01*
X192250Y90000D01*
G01X171263Y92837D02*
X172026Y93600D01*
X178680D01*
X180180Y92100D01*
X182800D01*
G01X184900Y106300D02*
X186698D01*
X186699Y106301D01*
X195569D01*
X195570Y106300D01*
X200100D01*
X200900Y105500D01*
X203050D01*
G01X192250Y90000D02*
Y90700D01*
X190025Y92925D01*
X186953D01*
X186128Y92100D01*
X182800D01*
G01X203050Y108060D02*
X201000D01*
X199860Y109200D01*
X184016D01*
X183166Y108350D01*
X180800D01*
G01Y114300D02*
Y118100D01*
X184200Y121500D01*
X192721D01*
G01D02*
X192882Y121339D01*
Y120118D01*
X194625Y118375D01*
X197817D01*
X199842Y120400D01*
X206504D01*
X207534Y119370D01*
G01X180800Y108350D02*
Y114300D01*
G01X188583Y240157D02*
X184397D01*
X171521Y227281D01*
Y192801D01*
X178695Y185627D01*
Y185153D01*
G01X188583Y232283D02*
X180307D01*
X174196Y226172D01*
Y201632D01*
X178563Y197265D01*
Y197014D01*
G01X188583Y156500D02*
X184700D01*
X181800Y159400D01*
G01X183583Y173228D02*
X180000Y169645D01*
Y161200D01*
X181800Y159400D01*
G01X207750Y224016D02*
X212181D01*
X213852Y222345D01*
Y221230D01*
G01X172835Y312992D02*
Y304665D01*
X181758Y295742D01*
X205463D01*
X225998Y275207D01*
Y217513D01*
X221923Y213438D01*
X214917D01*
X211012Y209533D01*
Y208233D01*
X201579Y198800D01*
X186138D01*
X180911Y193573D01*
Y188518D01*
X186229Y183200D01*
X192100D01*
X199900Y175400D01*
Y171945D01*
X206763Y165082D01*
G01D02*
X220200Y151645D01*
Y151000D01*
G01X217850Y206700D02*
Y205350D01*
X218534Y204666D01*
Y202560D01*
G01D02*
Y200534D01*
X215650Y197650D01*
Y197300D01*
G01D02*
Y196685D01*
X212345Y193380D01*
X207590D01*
G01Y190820D02*
X210780D01*
X211100Y190500D01*
X216000D01*
X216100Y190400D01*
G01X223200Y192850D02*
X222150D01*
X219700Y190400D01*
X216100D01*
G01X223200Y188800D02*
Y192850D01*
G01X207590Y188260D02*
Y186610D01*
X211900Y182300D01*
G01D02*
X212900Y181300D01*
X215650D01*
G01D02*
Y185300D01*
G01X183653Y191058D02*
X187642D01*
X187880Y190820D01*
X191410D01*
G01X205500Y176150D02*
Y178500D01*
X201900Y182100D01*
G01X191410Y193380D02*
X194020D01*
X196400Y191000D01*
Y187600D01*
X201900Y182100D01*
G01X209900Y176150D02*
Y179800D01*
X207400Y182300D01*
G01X191410Y195940D02*
X197060D01*
X200400Y192600D01*
Y189300D01*
X207400Y182300D01*
G01X219269Y216635D02*
Y218442D01*
X217790Y219921D01*
Y221230D01*
G01X220723Y291395D02*
Y296373D01*
X220891Y296541D01*
G01X212205Y312992D02*
Y309376D01*
X220891Y300690D01*
Y296541D01*
G01X209506Y229990D02*
X212030D01*
X213852Y228168D01*
Y226930D01*
G01X215916Y232222D02*
X217790Y230348D01*
Y226930D01*
G01X202363Y322835D02*
X211765D01*
X218369Y316231D01*
X222189D01*
G54D19*
X36900Y62600D03*
X51700Y59700D03*
X33100Y70800D03*
X40731Y70804D03*
X41442Y109358D03*
X48200Y191610D03*
X33700Y284000D03*
X125700Y54000D03*
X101001Y32537D03*
X120000Y23500D03*
X73500Y60500D03*
X188200Y70200D03*
X172887Y70136D03*
X201920Y113600D03*
X196171Y121500D03*
X219100Y185300D03*
G54D37*
X34342Y103542D03*
X57300Y118300D03*
X52618Y199384D03*
X109600Y51800D03*
X120100Y27400D03*
X218400Y115200D03*
G54D28*
X61000Y60500D03*
X14100Y48700D03*
X16813Y69474D03*
X51800Y38000D03*
X41300Y44400D03*
X56000Y60500D03*
X41300Y62600D03*
X49900Y16349D03*
X31600Y48100D03*
X29400Y58900D03*
X29650Y66500D03*
X67300Y38740D03*
X44416Y38922D03*
X66200Y60200D03*
X40631Y67104D03*
X71500Y53200D03*
X24900Y89600D03*
X12900Y107500D03*
X15800Y78400D03*
X16174Y73626D03*
X27042Y95162D03*
X45314Y102920D03*
X67282Y114234D03*
X69150Y105600D03*
X37000Y113300D03*
X41200Y95100D03*
X45900Y118700D03*
X55300Y165138D03*
X46000Y161800D03*
X17323Y159819D03*
X29232Y159877D03*
X49322Y183538D03*
X47699Y179634D03*
X12200Y201200D03*
X13646Y195250D03*
X11636Y227035D03*
X55800Y292900D03*
X43926Y277000D03*
X136400Y46500D03*
X77173Y23627D03*
X73400Y32000D03*
X145883Y54000D03*
X148558Y43046D03*
X75100Y68300D03*
X108300Y28700D03*
X112600D03*
X126100Y50300D03*
X121700D03*
X101800Y51800D03*
X116850Y34100D03*
X101200Y36500D03*
X129200Y27800D03*
X78600Y58500D03*
X75604Y76400D03*
X219082Y20786D03*
X178843Y62700D03*
X151336Y62300D03*
X193710Y20009D03*
X181167Y22264D03*
X172392Y18892D03*
X172328Y24231D03*
X205700Y55900D03*
X201600Y57100D03*
X161500Y65600D03*
X154424Y40024D03*
X183300Y54700D03*
X197500Y48750D03*
X178700Y52500D03*
X177637Y34565D03*
X192366Y61922D03*
X217732Y42900D03*
X223378Y30635D03*
X211300Y56100D03*
X214033Y44990D03*
X180600Y88400D03*
X165206Y110272D03*
X175766Y121643D03*
X164700Y82300D03*
X162610Y75430D03*
X171900Y105000D03*
X215000Y122900D03*
X182800Y92100D03*
X180800Y114300D03*
X223900Y203200D03*
X181800Y159400D03*
X215600Y151200D03*
X206763Y165082D03*
X218534Y202560D03*
X216100Y190400D03*
X211900Y182300D03*
X201900Y182100D03*
X207400Y182300D03*
X170617Y271803D03*
X220891Y296541D03*
X213762Y241107D03*
G54D55*
X22440Y303149D03*
X32283D03*
X42126D03*
X22440Y322835D03*
X32283D03*
X42126D03*
X182677Y303149D03*
X192520D03*
X202363D03*
X182677Y322835D03*
X192520D03*
X202363D03*
G54D46*
X38189Y220472D03*
X28346Y222440D03*
X38189Y251968D03*
Y244094D03*
Y236220D03*
Y228346D03*
X28346Y232283D03*
Y240157D03*
Y250000D03*
X12598Y312992D03*
X51968D03*
X198426Y220472D03*
X188583Y222440D03*
X198426Y251968D03*
Y244094D03*
Y236220D03*
Y228346D03*
X188583Y232283D03*
Y240157D03*
Y250000D03*
X172835Y312992D03*
X212205D03*
G54D64*
X186454Y283224D03*
X191054D03*
X195654D03*
G54D38*
X15900Y82800D03*
X39900Y80500D03*
X100900Y40600D03*
X132600Y34100D03*
Y47000D03*
X176300Y40400D03*
X183500Y39700D03*
X168966Y83430D03*
G54D29*
X51750Y113060D03*
Y110500D03*
Y107940D03*
X58250D03*
Y113060D03*
X163452Y40642D03*
Y38082D03*
Y35522D03*
X169952D03*
Y40642D03*
X170750Y54440D03*
Y57000D03*
Y59560D03*
X164250D03*
Y54440D03*
X203050Y108060D03*
Y105500D03*
Y102940D03*
X209550D03*
Y108060D03*
G54D47*
X40157Y211023D03*
X24409D03*
X40157Y261417D03*
X24409D03*
X200394Y211023D03*
X184646D03*
X200394Y261417D03*
X184646D03*
G54D56*
X106048Y44885D03*
X108018D03*
X109988D03*
X111958D03*
Y35685D03*
X109988D03*
X108018D03*
X106048D03*
X127770Y34391D03*
X125800D03*
X123830D03*
X121860D03*
Y43591D03*
X123830D03*
X125800D03*
X127770D03*
G54D65*
X178741Y282699D03*
G54D66*
Y285699D03*
G54D39*
X15900Y86400D03*
X39900Y84100D03*
X100900Y44200D03*
X132600Y37700D03*
Y50600D03*
X176300Y44000D03*
X183500Y43300D03*
X168966Y87030D03*
G54D57*
X105788Y6299D03*
X102638D03*
X99489D03*
X96339D03*
X93189D03*
X90040D03*
X86890D03*
G54D48*
X10519Y217435D03*
X8392Y207860D03*
X16977Y244294D03*
X16984Y248748D03*
X96200Y16400D03*
X133200Y17751D03*
X107506Y16719D03*
X116430Y16569D03*
X178563Y197014D03*
X178695Y185153D03*
X191391Y278906D03*
X195939Y278959D03*
G54D67*
G01X194583Y156500D02*
X199600D01*
G54D58*
X116339Y78740D03*
G54D49*
X22398Y154767D03*
G54D68*
G01X43900Y59600D02*
Y60100D01*
X47300Y63500D01*
Y65420D01*
G01X48150Y49500D02*
X48118Y49468D01*
X44505D01*
X43637Y48600D01*
X40950D01*
G01X30792Y103542D02*
Y105650D01*
X31442Y106300D01*
Y107815D01*
X31500Y107873D01*
Y108282D01*
G01X118100Y45000D02*
X119509Y43591D01*
X121860D01*
G01X106048Y44885D02*
Y43821D01*
X104765Y42538D01*
X103083D01*
X101195Y40650D01*
X100900D01*
G01X98071Y48175D02*
X105225D01*
X106048Y47352D01*
Y44885D01*
G01X132600Y34150D02*
X132359Y34391D01*
X127770D01*
G01X190850Y38500D02*
X184750D01*
X183500Y39750D01*
G01X214850Y115200D02*
X214620Y115430D01*
X209976D01*
G54D59*
X191900Y115700D03*
X185900D03*
G54D69*
G01X75600Y91500D02*
X73520Y93580D01*
X69500D01*
G01X21600Y81780D02*
X34400D01*
G01X21600D02*
X16970D01*
X15900Y82850D01*
G01X39900Y80550D02*
X38650D01*
X37420Y81780D01*
X34400D01*
G01X15900Y82850D02*
X15050D01*
X13150Y84750D01*
X12100D01*
G01X26700Y189160D02*
X21010D01*
G01X37190Y196840D02*
X38940D01*
X41128Y199028D01*
X48712D01*
X49068Y199384D01*
G01X140100Y14000D02*
Y11900D01*
X138839Y10639D01*
Y6299D01*
G01X198400Y61420D02*
Y57417D01*
X197760Y56777D01*
G01X192724Y80780D02*
X187400D01*
G01X168966Y83480D02*
X171666Y80780D01*
X174600D01*
G01X187400D02*
X174600D01*
G01X186100Y186500D02*
X187326D01*
X189086Y188260D01*
X191410D01*
G01X207590Y195940D02*
X209540D01*
X214450Y200850D01*
Y201900D01*
M02*
